FILE_TYPE = MACRO_DRAWING;
SET COLOR_WIRE YELLOW;
SET COLOR_PROP ORANGE;
SET COLOR_DOT WHITE;
SET COLOR_ARC YELLOW;
SET COLOR_BODY GREEN;
SET COLOR_NOTE PURPLE;
SET PROP_DISPLAY VALUE;
SET PAGE_NUMBER P98;
FORCEADD UNIVERSAL_GND..1
(-1400 -300);
FORCEPROP 3 LASTPIN (-1400 -250) SIG_NAME GND\g
J 0
(-1390 -240);
DISPLAY 0.659574 (-1390 -240);
PAINT MONO (-1390 -240);
DISPLAY INVISIBLE (-1390 -240);
FORCEPROP 2 LAST CDS_LIB logical_power
J 0
(-1400 -300);
PAINT MONO (-1400 -300);
DISPLAY INVISIBLE (-1400 -300);
FORCEPROP 1 LAST HDL_POWER GND
J 1
(-1375 -375);
DISPLAY 0.872340 (-1375 -375);
PAINT GREEN (-1375 -375);
DISPLAY INVISIBLE (-1375 -375);
FORCEPROP 1 LAST PATH I1
J 0
(-1325 -300);
DISPLAY 0.872340 (-1325 -300);
PAINT AQUA (-1325 -300);
DISPLAY INVISIBLE (-1325 -300);
FORCEADD OFFPAGE..1
(-2550 1725);
FORCEPROP 2 LAST $XR1 99 
J 0
(-2861 1725);
DISPLAY 0.638298 (-2861 1725);
PAINT MONO (-2861 1725);
FORCEPROP 2 LAST $XR0 51 
J 0
(-2771 1725);
DISPLAY 0.638298 (-2771 1725);
PAINT MONO (-2771 1725);
FORCEPROP 2 LAST CDS_LIB standard
J 0
(-2550 1725);
PAINT MONO (-2550 1725);
DISPLAY INVISIBLE (-2550 1725);
FORCEPROP 1 LAST OFFPAGE TRUE
J 0
(-2225 1600);
DISPLAY 0.872340 (-2225 1600);
DISPLAY INVISIBLE (-2225 1600);
FORCEPROP 1 LAST COMMENT_BODY TRUE
J 0
(-2425 1625);
DISPLAY 0.872340 (-2425 1625);
PAINT GREEN (-2425 1625);
DISPLAY INVISIBLE (-2425 1625);
FORCEPROP 2 LAST PATH I10
J 0
(-2500 1800);
DISPLAY 1.021277 (-2500 1800);
DISPLAY INVISIBLE (-2500 1800);
FORCEADD TAP..1
(25 3425);
FORCEPROP 3 LASTPIN (-25 3425) SIG_NAME M_A_CPU1_SA_DQ<18>
J 0
(-15 3435);
DISPLAY 0.659574 (-15 3435);
PAINT MONO (-15 3435);
DISPLAY INVISIBLE (-15 3435);
FORCEPROP 1 LASTPIN (-25 3425) BN 18
J 0
(-37 3433);
DISPLAY 0.680851 (-37 3433);
PAINT GREEN (-37 3433);
FORCEPROP 2 LAST CDS_LIB standard
J 0
(25 3425);
PAINT MONO (25 3425);
DISPLAY INVISIBLE (25 3425);
FORCEPROP 1 LAST BODY_TYPE PLUMBING
J 0
(25 3475);
DISPLAY 0.872340 (25 3475);
PAINT GREEN (25 3475);
DISPLAY INVISIBLE (25 3475);
FORCEPROP 1 LAST HDL_TAP TRUE
J 0
(350 3300);
DISPLAY 0.872340 (350 3300);
DISPLAY INVISIBLE (350 3300);
FORCEPROP 1 LAST PATH I100
J 0
(23 3425);
DISPLAY 0.872340 (23 3425);
PAINT GREEN (23 3425);
DISPLAY INVISIBLE (23 3425);
FORCEADD TAP..1
(25 3375);
FORCEPROP 3 LASTPIN (-25 3375) SIG_NAME M_A_CPU1_SA_DQ<17>
J 0
(-15 3385);
DISPLAY 0.659574 (-15 3385);
PAINT MONO (-15 3385);
DISPLAY INVISIBLE (-15 3385);
FORCEPROP 1 LASTPIN (-25 3375) BN 17
J 0
(-37 3383);
DISPLAY 0.680851 (-37 3383);
PAINT GREEN (-37 3383);
FORCEPROP 2 LAST CDS_LIB standard
J 0
(25 3375);
PAINT MONO (25 3375);
DISPLAY INVISIBLE (25 3375);
FORCEPROP 1 LAST BODY_TYPE PLUMBING
J 0
(25 3425);
DISPLAY 0.872340 (25 3425);
PAINT GREEN (25 3425);
DISPLAY INVISIBLE (25 3425);
FORCEPROP 1 LAST HDL_TAP TRUE
J 0
(350 3250);
DISPLAY 0.872340 (350 3250);
DISPLAY INVISIBLE (350 3250);
FORCEPROP 1 LAST PATH I101
J 0
(23 3375);
DISPLAY 0.872340 (23 3375);
PAINT GREEN (23 3375);
DISPLAY INVISIBLE (23 3375);
FORCEADD TAP..1
(25 3525);
FORCEPROP 3 LASTPIN (-25 3525) SIG_NAME M_A_CPU1_SA_DQ<20>
J 0
(-15 3535);
DISPLAY 0.659574 (-15 3535);
PAINT MONO (-15 3535);
DISPLAY INVISIBLE (-15 3535);
FORCEPROP 1 LASTPIN (-25 3525) BN 20
J 0
(-37 3533);
DISPLAY 0.680851 (-37 3533);
PAINT GREEN (-37 3533);
FORCEPROP 2 LAST CDS_LIB standard
J 0
(25 3525);
PAINT MONO (25 3525);
DISPLAY INVISIBLE (25 3525);
FORCEPROP 1 LAST BODY_TYPE PLUMBING
J 0
(25 3575);
DISPLAY 0.872340 (25 3575);
PAINT GREEN (25 3575);
DISPLAY INVISIBLE (25 3575);
FORCEPROP 1 LAST HDL_TAP TRUE
J 0
(350 3400);
DISPLAY 0.872340 (350 3400);
DISPLAY INVISIBLE (350 3400);
FORCEPROP 1 LAST PATH I102
J 0
(23 3525);
DISPLAY 0.872340 (23 3525);
PAINT GREEN (23 3525);
DISPLAY INVISIBLE (23 3525);
FORCEADD TAP..1
(25 3575);
FORCEPROP 3 LASTPIN (-25 3575) SIG_NAME M_A_CPU1_SA_DQ<21>
J 0
(-15 3585);
DISPLAY 0.659574 (-15 3585);
PAINT MONO (-15 3585);
DISPLAY INVISIBLE (-15 3585);
FORCEPROP 1 LASTPIN (-25 3575) BN 21
J 0
(-37 3583);
DISPLAY 0.680851 (-37 3583);
PAINT GREEN (-37 3583);
FORCEPROP 2 LAST CDS_LIB standard
J 0
(25 3575);
PAINT MONO (25 3575);
DISPLAY INVISIBLE (25 3575);
FORCEPROP 1 LAST BODY_TYPE PLUMBING
J 0
(25 3625);
DISPLAY 0.872340 (25 3625);
PAINT GREEN (25 3625);
DISPLAY INVISIBLE (25 3625);
FORCEPROP 1 LAST HDL_TAP TRUE
J 0
(350 3450);
DISPLAY 0.872340 (350 3450);
DISPLAY INVISIBLE (350 3450);
FORCEPROP 1 LAST PATH I103
J 0
(23 3575);
DISPLAY 0.872340 (23 3575);
PAINT GREEN (23 3575);
DISPLAY INVISIBLE (23 3575);
FORCEADD TAP..1
(25 3625);
FORCEPROP 3 LASTPIN (-25 3625) SIG_NAME M_A_CPU1_SA_DQ<22>
J 0
(-15 3635);
DISPLAY 0.659574 (-15 3635);
PAINT MONO (-15 3635);
DISPLAY INVISIBLE (-15 3635);
FORCEPROP 1 LASTPIN (-25 3625) BN 22
J 0
(-37 3633);
DISPLAY 0.680851 (-37 3633);
PAINT GREEN (-37 3633);
FORCEPROP 2 LAST CDS_LIB standard
J 0
(25 3625);
DISPLAY INVISIBLE (25 3625);
FORCEPROP 1 LAST BODY_TYPE PLUMBING
J 0
(25 3675);
DISPLAY 0.872340 (25 3675);
PAINT GREEN (25 3675);
DISPLAY INVISIBLE (25 3675);
FORCEPROP 1 LAST HDL_TAP TRUE
J 0
(350 3500);
DISPLAY 0.872340 (350 3500);
DISPLAY INVISIBLE (350 3500);
FORCEPROP 1 LAST PATH I104
J 0
(23 3625);
DISPLAY 0.872340 (23 3625);
PAINT GREEN (23 3625);
DISPLAY INVISIBLE (23 3625);
FORCEADD TAP..1
(25 3675);
FORCEPROP 3 LASTPIN (-25 3675) SIG_NAME M_A_CPU1_SA_DQ<23>
J 0
(-15 3685);
DISPLAY 0.659574 (-15 3685);
PAINT MONO (-15 3685);
DISPLAY INVISIBLE (-15 3685);
FORCEPROP 1 LASTPIN (-25 3675) BN 23
J 0
(-37 3683);
DISPLAY 0.680851 (-37 3683);
PAINT GREEN (-37 3683);
FORCEPROP 2 LAST CDS_LIB standard
J 0
(25 3675);
DISPLAY INVISIBLE (25 3675);
FORCEPROP 1 LAST BODY_TYPE PLUMBING
J 0
(25 3725);
DISPLAY 0.872340 (25 3725);
PAINT GREEN (25 3725);
DISPLAY INVISIBLE (25 3725);
FORCEPROP 1 LAST HDL_TAP TRUE
J 0
(350 3550);
DISPLAY 0.872340 (350 3550);
DISPLAY INVISIBLE (350 3550);
FORCEPROP 1 LAST PATH I105
J 0
(23 3675);
DISPLAY 0.872340 (23 3675);
PAINT GREEN (23 3675);
DISPLAY INVISIBLE (23 3675);
FORCEADD TAP..1
(25 3725);
FORCEPROP 3 LASTPIN (-25 3725) SIG_NAME M_A_CPU1_SA_DQ<24>
J 0
(-15 3735);
DISPLAY 0.659574 (-15 3735);
PAINT MONO (-15 3735);
DISPLAY INVISIBLE (-15 3735);
FORCEPROP 1 LASTPIN (-25 3725) BN 24
J 0
(-37 3733);
DISPLAY 0.680851 (-37 3733);
PAINT GREEN (-37 3733);
FORCEPROP 2 LAST CDS_LIB standard
J 0
(25 3725);
DISPLAY INVISIBLE (25 3725);
FORCEPROP 1 LAST BODY_TYPE PLUMBING
J 0
(25 3775);
DISPLAY 0.872340 (25 3775);
PAINT GREEN (25 3775);
DISPLAY INVISIBLE (25 3775);
FORCEPROP 1 LAST HDL_TAP TRUE
J 0
(350 3600);
DISPLAY 0.872340 (350 3600);
DISPLAY INVISIBLE (350 3600);
FORCEPROP 1 LAST PATH I106
J 0
(23 3725);
DISPLAY 0.872340 (23 3725);
PAINT GREEN (23 3725);
DISPLAY INVISIBLE (23 3725);
FORCEADD TAP..1
(25 3775);
FORCEPROP 3 LASTPIN (-25 3775) SIG_NAME M_A_CPU1_SA_DQ<25>
J 0
(-15 3785);
DISPLAY 0.659574 (-15 3785);
PAINT MONO (-15 3785);
DISPLAY INVISIBLE (-15 3785);
FORCEPROP 1 LASTPIN (-25 3775) BN 25
J 0
(-37 3783);
DISPLAY 0.680851 (-37 3783);
PAINT GREEN (-37 3783);
FORCEPROP 2 LAST CDS_LIB standard
J 0
(25 3775);
DISPLAY INVISIBLE (25 3775);
FORCEPROP 1 LAST BODY_TYPE PLUMBING
J 0
(25 3825);
DISPLAY 0.872340 (25 3825);
PAINT GREEN (25 3825);
DISPLAY INVISIBLE (25 3825);
FORCEPROP 1 LAST HDL_TAP TRUE
J 0
(350 3650);
DISPLAY 0.872340 (350 3650);
DISPLAY INVISIBLE (350 3650);
FORCEPROP 1 LAST PATH I107
J 0
(23 3775);
DISPLAY 0.872340 (23 3775);
PAINT GREEN (23 3775);
DISPLAY INVISIBLE (23 3775);
FORCEADD TAP..1
(25 3825);
FORCEPROP 3 LASTPIN (-25 3825) SIG_NAME M_A_CPU1_SA_DQ<26>
J 0
(-15 3835);
DISPLAY 0.659574 (-15 3835);
PAINT MONO (-15 3835);
DISPLAY INVISIBLE (-15 3835);
FORCEPROP 1 LASTPIN (-25 3825) BN 26
J 0
(-37 3833);
DISPLAY 0.680851 (-37 3833);
PAINT GREEN (-37 3833);
FORCEPROP 2 LAST CDS_LIB standard
J 0
(25 3825);
DISPLAY INVISIBLE (25 3825);
FORCEPROP 1 LAST BODY_TYPE PLUMBING
J 0
(25 3875);
DISPLAY 0.872340 (25 3875);
PAINT GREEN (25 3875);
DISPLAY INVISIBLE (25 3875);
FORCEPROP 1 LAST HDL_TAP TRUE
J 0
(350 3700);
DISPLAY 0.872340 (350 3700);
DISPLAY INVISIBLE (350 3700);
FORCEPROP 1 LAST PATH I108
J 0
(23 3825);
DISPLAY 0.872340 (23 3825);
PAINT GREEN (23 3825);
DISPLAY INVISIBLE (23 3825);
FORCEADD OFFPAGE..1
(-2550 4100);
FORCEPROP 2 LAST $XR1 99 
J 0
(-2861 4100);
DISPLAY 0.638298 (-2861 4100);
PAINT MONO (-2861 4100);
FORCEPROP 2 LAST $XR0 51 
J 0
(-2771 4100);
DISPLAY 0.638298 (-2771 4100);
PAINT MONO (-2771 4100);
FORCEPROP 2 LAST CDS_LIB standard
J 0
(-2550 4100);
PAINT MONO (-2550 4100);
DISPLAY INVISIBLE (-2550 4100);
FORCEPROP 1 LAST OFFPAGE TRUE
J 0
(-2225 3975);
DISPLAY 0.872340 (-2225 3975);
DISPLAY INVISIBLE (-2225 3975);
FORCEPROP 1 LAST COMMENT_BODY TRUE
J 0
(-2425 4000);
DISPLAY 0.872340 (-2425 4000);
PAINT GREEN (-2425 4000);
DISPLAY INVISIBLE (-2425 4000);
FORCEPROP 2 LAST PATH I109
J 0
(-2500 4175);
DISPLAY 1.021277 (-2500 4175);
DISPLAY INVISIBLE (-2500 4175);
FORCEADD Q_RES..2
(-1400 -75);
FORCEPROP 1 LAST PART_NUMBER CS31002FB08
J 0
(-1360 -200);
DISPLAY 0.978723 (-1360 -200);
DISPLAY INVISIBLE (-1360 -200);
FORCEPROP 1 LAST WATTAGE 1/16W
J 0
(-1360 -100);
DISPLAY 0.978723 (-1360 -100);
FORCEPROP 1 LAST TOLERANCE 1%
J 0
(-1355 -50);
DISPLAY 0.978723 (-1355 -50);
FORCEPROP 1 LAST MATERIAL CHIP
J 0
(-1360 -150);
DISPLAY 0.978723 (-1360 -150);
FORCEPROP 1 LAST PACK_TYPE 0402LF
J 0
(-1360 -250);
DISPLAY 0.978723 (-1360 -250);
FORCEPROP 1 LAST VALUE 10K
J 0
(-1355 0);
DISPLAY 0.978723 (-1355 0);
FORCEPROP 1 LAST $LOCATION R42
J 0
(-1355 50);
DISPLAY 0.978723 (-1355 50);
FORCEPROP 1 LASTPIN (-1400 25) $PN 1
J 0
(-1395 -13);
DISPLAY 0.787234 (-1395 -13);
FORCEPROP 1 LASTPIN (-1400 -175) $PN 2
J 0
(-1395 -165);
DISPLAY 0.787234 (-1395 -165);
FORCEPROP 2 LAST CDS_LIB pure_quanta
J 0
(-1400 -75);
PAINT MONO (-1400 -75);
DISPLAY INVISIBLE (-1400 -75);
FORCEPROP 2 LAST CDS_LOCATION R42
J 0
(-1350 150);
DISPLAY 1.021277 (-1350 150);
DISPLAY INVISIBLE (-1350 150);
FORCEPROP 2 LAST $SEC 1
J 0
(-1350 150);
DISPLAY 0.680851 (-1350 150);
PAINT MONO (-1350 150);
DISPLAY INVISIBLE (-1350 150);
FORCEPROP 2 LAST CDS_SEC 1
J 0
(-1350 150);
DISPLAY 1.021277 (-1350 150);
DISPLAY INVISIBLE (-1350 150);
FORCEPROP 1 LAST PATH I11
J 0
(-1350 100);
DISPLAY 0.978723 (-1350 100);
PAINT WHITE (-1350 100);
DISPLAY INVISIBLE (-1350 100);
FORCEADD TAP..1
R 2
(-1625 3875);
FORCEPROP 3 LASTPIN (-1575 3875) SIG_NAME M_A_CPU1_SA_CA<2>
J 0
(-1565 3885);
DISPLAY 0.659574 (-1565 3885);
PAINT MONO (-1565 3885);
DISPLAY INVISIBLE (-1565 3885);
FORCEPROP 1 LASTPIN (-1575 3875) BN 2
J 2
(-1563 3883);
DISPLAY 0.680851 (-1563 3883);
PAINT GREEN (-1563 3883);
FORCEPROP 2 LAST CDS_LIB standard
J 0
(-1625 3875);
DISPLAY INVISIBLE (-1625 3875);
FORCEPROP 1 LAST BODY_TYPE PLUMBING
J 2
(-1625 3925);
DISPLAY 0.872340 (-1625 3925);
PAINT GREEN (-1625 3925);
DISPLAY INVISIBLE (-1625 3925);
FORCEPROP 1 LAST HDL_TAP TRUE
J 2
(-1950 3750);
DISPLAY 0.872340 (-1950 3750);
DISPLAY INVISIBLE (-1950 3750);
FORCEPROP 1 LAST PATH I110
J 2
(-1623 3875);
DISPLAY 0.872340 (-1623 3875);
PAINT GREEN (-1623 3875);
DISPLAY INVISIBLE (-1623 3875);
FORCEADD TAP..1
R 2
(-1625 3925);
FORCEPROP 3 LASTPIN (-1575 3925) SIG_NAME M_A_CPU1_SA_CA<3>
J 0
(-1565 3935);
DISPLAY 0.659574 (-1565 3935);
PAINT MONO (-1565 3935);
DISPLAY INVISIBLE (-1565 3935);
FORCEPROP 1 LASTPIN (-1575 3925) BN 3
J 2
(-1563 3933);
DISPLAY 0.680851 (-1563 3933);
PAINT GREEN (-1563 3933);
FORCEPROP 2 LAST CDS_LIB standard
J 0
(-1625 3925);
DISPLAY INVISIBLE (-1625 3925);
FORCEPROP 1 LAST BODY_TYPE PLUMBING
J 2
(-1625 3975);
DISPLAY 0.872340 (-1625 3975);
PAINT GREEN (-1625 3975);
DISPLAY INVISIBLE (-1625 3975);
FORCEPROP 1 LAST HDL_TAP TRUE
J 2
(-1950 3800);
DISPLAY 0.872340 (-1950 3800);
DISPLAY INVISIBLE (-1950 3800);
FORCEPROP 1 LAST PATH I111
J 2
(-1623 3925);
DISPLAY 0.872340 (-1623 3925);
PAINT GREEN (-1623 3925);
DISPLAY INVISIBLE (-1623 3925);
FORCEADD TAP..1
R 2
(-1625 3975);
FORCEPROP 3 LASTPIN (-1575 3975) SIG_NAME M_A_CPU1_SA_CA<4>
J 0
(-1565 3985);
DISPLAY 0.659574 (-1565 3985);
PAINT MONO (-1565 3985);
DISPLAY INVISIBLE (-1565 3985);
FORCEPROP 1 LASTPIN (-1575 3975) BN 4
J 2
(-1563 3983);
DISPLAY 0.680851 (-1563 3983);
PAINT GREEN (-1563 3983);
FORCEPROP 2 LAST CDS_LIB standard
J 0
(-1625 3975);
DISPLAY INVISIBLE (-1625 3975);
FORCEPROP 1 LAST BODY_TYPE PLUMBING
J 2
(-1625 4025);
DISPLAY 0.872340 (-1625 4025);
PAINT GREEN (-1625 4025);
DISPLAY INVISIBLE (-1625 4025);
FORCEPROP 1 LAST HDL_TAP TRUE
J 2
(-1950 3850);
DISPLAY 0.872340 (-1950 3850);
DISPLAY INVISIBLE (-1950 3850);
FORCEPROP 1 LAST PATH I112
J 2
(-1623 3975);
DISPLAY 0.872340 (-1623 3975);
PAINT GREEN (-1623 3975);
DISPLAY INVISIBLE (-1623 3975);
FORCEADD TAP..1
R 2
(-1625 4075);
FORCEPROP 3 LASTPIN (-1575 4075) SIG_NAME M_A_CPU1_SA_CA<6>
J 0
(-1565 4085);
DISPLAY 0.659574 (-1565 4085);
PAINT MONO (-1565 4085);
DISPLAY INVISIBLE (-1565 4085);
FORCEPROP 1 LASTPIN (-1575 4075) BN 6
J 2
(-1563 4083);
DISPLAY 0.680851 (-1563 4083);
PAINT GREEN (-1563 4083);
FORCEPROP 2 LAST CDS_LIB standard
J 0
(-1625 4075);
DISPLAY INVISIBLE (-1625 4075);
FORCEPROP 1 LAST BODY_TYPE PLUMBING
J 2
(-1625 4125);
DISPLAY 0.872340 (-1625 4125);
PAINT GREEN (-1625 4125);
DISPLAY INVISIBLE (-1625 4125);
FORCEPROP 1 LAST HDL_TAP TRUE
J 2
(-1950 3950);
DISPLAY 0.872340 (-1950 3950);
DISPLAY INVISIBLE (-1950 3950);
FORCEPROP 1 LAST PATH I113
J 2
(-1623 4075);
DISPLAY 0.872340 (-1623 4075);
PAINT GREEN (-1623 4075);
DISPLAY INVISIBLE (-1623 4075);
FORCEADD TAP..1
R 2
(-1625 4025);
FORCEPROP 3 LASTPIN (-1575 4025) SIG_NAME M_A_CPU1_SA_CA<5>
J 0
(-1565 4035);
DISPLAY 0.659574 (-1565 4035);
PAINT MONO (-1565 4035);
DISPLAY INVISIBLE (-1565 4035);
FORCEPROP 1 LASTPIN (-1575 4025) BN 5
J 2
(-1563 4033);
DISPLAY 0.680851 (-1563 4033);
PAINT GREEN (-1563 4033);
FORCEPROP 2 LAST CDS_LIB standard
J 0
(-1625 4025);
DISPLAY INVISIBLE (-1625 4025);
FORCEPROP 1 LAST BODY_TYPE PLUMBING
J 2
(-1625 4075);
DISPLAY 0.872340 (-1625 4075);
PAINT GREEN (-1625 4075);
DISPLAY INVISIBLE (-1625 4075);
FORCEPROP 1 LAST HDL_TAP TRUE
J 2
(-1950 3900);
DISPLAY 0.872340 (-1950 3900);
DISPLAY INVISIBLE (-1950 3900);
FORCEPROP 1 LAST PATH I114
J 2
(-1623 4025);
DISPLAY 0.872340 (-1623 4025);
PAINT GREEN (-1623 4025);
DISPLAY INVISIBLE (-1623 4025);
FORCEADD TAP..1
(25 3975);
FORCEPROP 3 LASTPIN (-25 3975) SIG_NAME M_A_CPU1_SA_DQ<29>
J 0
(-15 3985);
DISPLAY 0.659574 (-15 3985);
PAINT MONO (-15 3985);
DISPLAY INVISIBLE (-15 3985);
FORCEPROP 1 LASTPIN (-25 3975) BN 29
J 0
(-37 3983);
DISPLAY 0.680851 (-37 3983);
PAINT GREEN (-37 3983);
FORCEPROP 2 LAST CDS_LIB standard
J 0
(25 3975);
DISPLAY INVISIBLE (25 3975);
FORCEPROP 1 LAST BODY_TYPE PLUMBING
J 0
(25 4025);
DISPLAY 0.872340 (25 4025);
PAINT GREEN (25 4025);
DISPLAY INVISIBLE (25 4025);
FORCEPROP 1 LAST HDL_TAP TRUE
J 0
(350 3850);
DISPLAY 0.872340 (350 3850);
DISPLAY INVISIBLE (350 3850);
FORCEPROP 1 LAST PATH I115
J 0
(23 3975);
DISPLAY 0.872340 (23 3975);
PAINT GREEN (23 3975);
DISPLAY INVISIBLE (23 3975);
FORCEADD TAP..1
(25 3875);
FORCEPROP 3 LASTPIN (-25 3875) SIG_NAME M_A_CPU1_SA_DQ<27>
J 0
(-15 3885);
DISPLAY 0.659574 (-15 3885);
PAINT MONO (-15 3885);
DISPLAY INVISIBLE (-15 3885);
FORCEPROP 1 LASTPIN (-25 3875) BN 27
J 0
(-37 3883);
DISPLAY 0.680851 (-37 3883);
PAINT GREEN (-37 3883);
FORCEPROP 2 LAST CDS_LIB standard
J 0
(25 3875);
DISPLAY INVISIBLE (25 3875);
FORCEPROP 1 LAST BODY_TYPE PLUMBING
J 0
(25 3925);
DISPLAY 0.872340 (25 3925);
PAINT GREEN (25 3925);
DISPLAY INVISIBLE (25 3925);
FORCEPROP 1 LAST HDL_TAP TRUE
J 0
(350 3750);
DISPLAY 0.872340 (350 3750);
DISPLAY INVISIBLE (350 3750);
FORCEPROP 1 LAST PATH I116
J 0
(23 3875);
DISPLAY 0.872340 (23 3875);
PAINT GREEN (23 3875);
DISPLAY INVISIBLE (23 3875);
FORCEADD TAP..1
(25 3925);
FORCEPROP 3 LASTPIN (-25 3925) SIG_NAME M_A_CPU1_SA_DQ<28>
J 0
(-15 3935);
DISPLAY 0.659574 (-15 3935);
PAINT MONO (-15 3935);
DISPLAY INVISIBLE (-15 3935);
FORCEPROP 1 LASTPIN (-25 3925) BN 28
J 0
(-37 3933);
DISPLAY 0.680851 (-37 3933);
PAINT GREEN (-37 3933);
FORCEPROP 2 LAST CDS_LIB standard
J 0
(25 3925);
DISPLAY INVISIBLE (25 3925);
FORCEPROP 1 LAST BODY_TYPE PLUMBING
J 0
(25 3975);
DISPLAY 0.872340 (25 3975);
PAINT GREEN (25 3975);
DISPLAY INVISIBLE (25 3975);
FORCEPROP 1 LAST HDL_TAP TRUE
J 0
(350 3800);
DISPLAY 0.872340 (350 3800);
DISPLAY INVISIBLE (350 3800);
FORCEPROP 1 LAST PATH I117
J 0
(23 3925);
DISPLAY 0.872340 (23 3925);
PAINT GREEN (23 3925);
DISPLAY INVISIBLE (23 3925);
FORCEADD TAP..1
(25 4025);
FORCEPROP 3 LASTPIN (-25 4025) SIG_NAME M_A_CPU1_SA_DQ<30>
J 0
(-15 4035);
DISPLAY 0.659574 (-15 4035);
PAINT MONO (-15 4035);
DISPLAY INVISIBLE (-15 4035);
FORCEPROP 1 LASTPIN (-25 4025) BN 30
J 0
(-37 4033);
DISPLAY 0.680851 (-37 4033);
PAINT GREEN (-37 4033);
FORCEPROP 2 LAST CDS_LIB standard
J 0
(25 4025);
DISPLAY INVISIBLE (25 4025);
FORCEPROP 1 LAST BODY_TYPE PLUMBING
J 0
(25 4075);
DISPLAY 0.872340 (25 4075);
PAINT GREEN (25 4075);
DISPLAY INVISIBLE (25 4075);
FORCEPROP 1 LAST HDL_TAP TRUE
J 0
(350 3900);
DISPLAY 0.872340 (350 3900);
DISPLAY INVISIBLE (350 3900);
FORCEPROP 1 LAST PATH I118
J 0
(23 4025);
DISPLAY 0.872340 (23 4025);
PAINT GREEN (23 4025);
DISPLAY INVISIBLE (23 4025);
FORCEADD TAP..1
(25 4075);
FORCEPROP 3 LASTPIN (-25 4075) SIG_NAME M_A_CPU1_SA_DQ<31>
J 0
(-15 4085);
DISPLAY 0.659574 (-15 4085);
PAINT MONO (-15 4085);
DISPLAY INVISIBLE (-15 4085);
FORCEPROP 1 LASTPIN (-25 4075) BN 31
J 0
(-37 4083);
DISPLAY 0.680851 (-37 4083);
PAINT GREEN (-37 4083);
FORCEPROP 2 LAST CDS_LIB standard
J 0
(25 4075);
DISPLAY INVISIBLE (25 4075);
FORCEPROP 1 LAST BODY_TYPE PLUMBING
J 0
(25 4125);
DISPLAY 0.872340 (25 4125);
PAINT GREEN (25 4125);
DISPLAY INVISIBLE (25 4125);
FORCEPROP 1 LAST HDL_TAP TRUE
J 0
(350 3950);
DISPLAY 0.872340 (350 3950);
DISPLAY INVISIBLE (350 3950);
FORCEPROP 1 LAST PATH I119
J 0
(23 4075);
DISPLAY 0.872340 (23 4075);
PAINT GREEN (23 4075);
DISPLAY INVISIBLE (23 4075);
FORCEADD SCONN288_ADR50017P130CC..1
(-800 2350);
FORCEPROP 1 LAST PART_NUMBER DFHST8FS461
J 0
(-1245 4372);
DISPLAY 0.723404 (-1245 4372);
PAINT GREEN (-1245 4372);
DISPLAY INVISIBLE (-1245 4372);
FORCEPROP 1 LAST MATERIAL IO
J 0
(-1245 4245);
DISPLAY 0.723404 (-1245 4245);
PAINT GREEN (-1245 4245);
FORCEPROP 2 LAST VALUE SCONN288_ADR50017-P130CC
J 0
(-1250 4475);
DISPLAY 1.021277 (-1250 4475);
FORCEPROP 2 LAST PART_TYPE SMLF
J 0
(-1250 4525);
DISPLAY 1.021277 (-1250 4525);
FORCEPROP 1 LAST $LOCATION J17
J 0
(-1250 4425);
DISPLAY 0.723404 (-1250 4425);
PAINT GREEN (-1250 4425);
FORCEPROP 0 LASTPIN (-1400 1725) $PN 62
J 2
(-1410 1735);
DISPLAY 0.680851 (-1410 1735);
PAINT MONO (-1410 1735);
FORCEPROP 0 LASTPIN (-1400 3775) $PN 66
J 2
(-1410 3785);
DISPLAY 0.680851 (-1410 3785);
PAINT MONO (-1410 3785);
FORCEPROP 0 LASTPIN (-1400 3375) $PN 76
J 2
(-1410 3385);
DISPLAY 0.680851 (-1410 3385);
PAINT MONO (-1410 3385);
FORCEPROP 0 LASTPIN (-1400 3825) $PN 211
J 2
(-1410 3835);
DISPLAY 0.680851 (-1410 3835);
PAINT MONO (-1410 3835);
FORCEPROP 0 LASTPIN (-1400 3425) $PN 221
J 2
(-1410 3435);
DISPLAY 0.680851 (-1410 3435);
PAINT MONO (-1410 3435);
FORCEPROP 0 LASTPIN (-1400 3875) $PN 68
J 2
(-1410 3885);
DISPLAY 0.680851 (-1410 3885);
PAINT MONO (-1410 3885);
FORCEPROP 0 LASTPIN (-1400 3475) $PN 78
J 2
(-1410 3485);
DISPLAY 0.680851 (-1410 3485);
PAINT MONO (-1410 3485);
FORCEPROP 0 LASTPIN (-1400 3925) $PN 213
J 2
(-1410 3935);
DISPLAY 0.680851 (-1410 3935);
PAINT MONO (-1410 3935);
FORCEPROP 0 LASTPIN (-1400 3525) $PN 223
J 2
(-1410 3535);
DISPLAY 0.680851 (-1410 3535);
PAINT MONO (-1410 3535);
FORCEPROP 0 LASTPIN (-1400 3975) $PN 70
J 2
(-1410 3985);
DISPLAY 0.680851 (-1410 3985);
PAINT MONO (-1410 3985);
FORCEPROP 0 LASTPIN (-1400 3575) $PN 80
J 2
(-1410 3585);
DISPLAY 0.680851 (-1410 3585);
PAINT MONO (-1410 3585);
FORCEPROP 0 LASTPIN (-1400 4025) $PN 215
J 2
(-1410 4035);
DISPLAY 0.680851 (-1410 4035);
PAINT MONO (-1410 4035);
FORCEPROP 0 LASTPIN (-1400 3625) $PN 225
J 2
(-1410 3635);
DISPLAY 0.680851 (-1410 3635);
PAINT MONO (-1410 3635);
FORCEPROP 0 LASTPIN (-1400 4075) $PN 72
J 2
(-1410 4085);
DISPLAY 0.680851 (-1410 4085);
PAINT MONO (-1410 4085);
FORCEPROP 0 LASTPIN (-1400 3675) $PN 82
J 2
(-1410 3685);
DISPLAY 0.680851 (-1410 3685);
PAINT MONO (-1410 3685);
FORCEPROP 0 LASTPIN (-1400 2325) $PN 51
J 2
(-1410 2335);
DISPLAY 0.680851 (-1410 2335);
PAINT MONO (-1410 2335);
FORCEPROP 0 LASTPIN (-1400 1875) $PN 96
J 2
(-1410 1885);
DISPLAY 0.680851 (-1410 1885);
PAINT MONO (-1410 1885);
FORCEPROP 0 LASTPIN (-1400 2375) $PN 53
J 2
(-1410 2385);
DISPLAY 0.680851 (-1410 2385);
PAINT MONO (-1410 2385);
FORCEPROP 0 LASTPIN (-1400 1925) $PN 98
J 2
(-1410 1935);
DISPLAY 0.680851 (-1410 1935);
PAINT MONO (-1410 1935);
FORCEPROP 0 LASTPIN (-1400 2425) $PN 196
J 2
(-1410 2435);
DISPLAY 0.680851 (-1410 2435);
PAINT MONO (-1410 2435);
FORCEPROP 0 LASTPIN (-1400 1975) $PN 241
J 2
(-1410 1985);
DISPLAY 0.680851 (-1410 1985);
PAINT MONO (-1410 1985);
FORCEPROP 0 LASTPIN (-1400 2475) $PN 198
J 2
(-1410 2485);
DISPLAY 0.680851 (-1410 2485);
PAINT MONO (-1410 2485);
FORCEPROP 0 LASTPIN (-1400 2025) $PN 243
J 2
(-1410 2035);
DISPLAY 0.680851 (-1410 2035);
PAINT MONO (-1410 2035);
FORCEPROP 0 LASTPIN (-1400 2525) $PN 58
J 2
(-1410 2535);
DISPLAY 0.680851 (-1410 2535);
PAINT MONO (-1410 2535);
FORCEPROP 0 LASTPIN (-1400 2075) $PN 89
J 2
(-1410 2085);
DISPLAY 0.680851 (-1410 2085);
PAINT MONO (-1410 2085);
FORCEPROP 0 LASTPIN (-1400 2575) $PN 60
J 2
(-1410 2585);
DISPLAY 0.680851 (-1410 2585);
PAINT MONO (-1410 2585);
FORCEPROP 0 LASTPIN (-1400 2125) $PN 91
J 2
(-1410 2135);
DISPLAY 0.680851 (-1410 2135);
PAINT MONO (-1410 2135);
FORCEPROP 0 LASTPIN (-1400 2625) $PN 203
J 2
(-1410 2635);
DISPLAY 0.680851 (-1410 2635);
PAINT MONO (-1410 2635);
FORCEPROP 0 LASTPIN (-1400 2175) $PN 234
J 2
(-1410 2185);
DISPLAY 0.680851 (-1410 2185);
PAINT MONO (-1410 2185);
FORCEPROP 0 LASTPIN (-1400 2675) $PN 205
J 2
(-1410 2685);
DISPLAY 0.680851 (-1410 2685);
PAINT MONO (-1410 2685);
FORCEPROP 0 LASTPIN (-1400 2225) $PN 236
J 2
(-1410 2235);
DISPLAY 0.680851 (-1410 2235);
PAINT MONO (-1410 2235);
FORCEPROP 0 LASTPIN (-1400 2775) $PN 218
J 2
(-1410 2785);
DISPLAY 0.680851 (-1410 2785);
PAINT MONO (-1410 2785);
FORCEPROP 0 LASTPIN (-1400 2825) $PN 217
J 2
(-1410 2835);
DISPLAY 0.680851 (-1410 2835);
PAINT MONO (-1410 2835);
FORCEPROP 0 LASTPIN (-1400 3075) $PN 64
J 2
(-1410 3085);
DISPLAY 0.680851 (-1410 3085);
PAINT MONO (-1410 3085);
FORCEPROP 0 LASTPIN (-1400 2925) $PN 84
J 2
(-1410 2935);
DISPLAY 0.680851 (-1410 2935);
PAINT MONO (-1410 2935);
FORCEPROP 0 LASTPIN (-1400 3125) $PN 209
J 2
(-1410 3135);
DISPLAY 0.680851 (-1410 3135);
PAINT MONO (-1410 3135);
FORCEPROP 0 LASTPIN (-1400 2975) $PN 229
J 2
(-1410 2985);
DISPLAY 0.680851 (-1410 2985);
PAINT MONO (-1410 2985);
FORCEPROP 0 LASTPIN (-200 2525) $PN 7
J 0
(-190 2535);
DISPLAY 0.680851 (-190 2535);
PAINT MONO (-190 2535);
FORCEPROP 0 LASTPIN (-200 875) $PN 100
J 0
(-190 885);
DISPLAY 0.680851 (-190 885);
PAINT MONO (-190 885);
FORCEPROP 0 LASTPIN (-200 2575) $PN 9
J 0
(-190 2585);
DISPLAY 0.680851 (-190 2585);
PAINT MONO (-190 2585);
FORCEPROP 0 LASTPIN (-200 925) $PN 102
J 0
(-190 935);
DISPLAY 0.680851 (-190 935);
PAINT MONO (-190 935);
FORCEPROP 0 LASTPIN (-200 2625) $PN 152
J 0
(-190 2635);
DISPLAY 0.680851 (-190 2635);
PAINT MONO (-190 2635);
FORCEPROP 0 LASTPIN (-200 975) $PN 245
J 0
(-190 985);
DISPLAY 0.680851 (-190 985);
PAINT MONO (-190 985);
FORCEPROP 0 LASTPIN (-200 2675) $PN 154
J 0
(-190 2685);
DISPLAY 0.680851 (-190 2685);
PAINT MONO (-190 2685);
FORCEPROP 0 LASTPIN (-200 1025) $PN 247
J 0
(-190 1035);
DISPLAY 0.680851 (-190 1035);
PAINT MONO (-190 1035);
FORCEPROP 0 LASTPIN (-200 2725) $PN 14
J 0
(-190 2735);
DISPLAY 0.680851 (-190 2735);
PAINT MONO (-190 2735);
FORCEPROP 0 LASTPIN (-200 1075) $PN 107
J 0
(-190 1085);
DISPLAY 0.680851 (-190 1085);
PAINT MONO (-190 1085);
FORCEPROP 0 LASTPIN (-200 2775) $PN 16
J 0
(-190 2785);
DISPLAY 0.680851 (-190 2785);
PAINT MONO (-190 2785);
FORCEPROP 0 LASTPIN (-200 1125) $PN 109
J 0
(-190 1135);
DISPLAY 0.680851 (-190 1135);
PAINT MONO (-190 1135);
FORCEPROP 0 LASTPIN (-200 2825) $PN 159
J 0
(-190 2835);
DISPLAY 0.680851 (-190 2835);
PAINT MONO (-190 2835);
FORCEPROP 0 LASTPIN (-200 1175) $PN 252
J 0
(-190 1185);
DISPLAY 0.680851 (-190 1185);
PAINT MONO (-190 1185);
FORCEPROP 0 LASTPIN (-200 2875) $PN 161
J 0
(-190 2885);
DISPLAY 0.680851 (-190 2885);
PAINT MONO (-190 2885);
FORCEPROP 0 LASTPIN (-200 1225) $PN 254
J 0
(-190 1235);
DISPLAY 0.680851 (-190 1235);
PAINT MONO (-190 1235);
FORCEPROP 0 LASTPIN (-200 2925) $PN 18
J 0
(-190 2935);
DISPLAY 0.680851 (-190 2935);
PAINT MONO (-190 2935);
FORCEPROP 0 LASTPIN (-200 1275) $PN 111
J 0
(-190 1285);
DISPLAY 0.680851 (-190 1285);
PAINT MONO (-190 1285);
FORCEPROP 0 LASTPIN (-200 2975) $PN 20
J 0
(-190 2985);
DISPLAY 0.680851 (-190 2985);
PAINT MONO (-190 2985);
FORCEPROP 0 LASTPIN (-200 1325) $PN 113
J 0
(-190 1335);
DISPLAY 0.680851 (-190 1335);
PAINT MONO (-190 1335);
FORCEPROP 0 LASTPIN (-200 3025) $PN 163
J 0
(-190 3035);
DISPLAY 0.680851 (-190 3035);
PAINT MONO (-190 3035);
FORCEPROP 0 LASTPIN (-200 1375) $PN 256
J 0
(-190 1385);
DISPLAY 0.680851 (-190 1385);
PAINT MONO (-190 1385);
FORCEPROP 0 LASTPIN (-200 3075) $PN 165
J 0
(-190 3085);
DISPLAY 0.680851 (-190 3085);
PAINT MONO (-190 3085);
FORCEPROP 0 LASTPIN (-200 1425) $PN 258
J 0
(-190 1435);
DISPLAY 0.680851 (-190 1435);
PAINT MONO (-190 1435);
FORCEPROP 0 LASTPIN (-200 3125) $PN 25
J 0
(-190 3135);
DISPLAY 0.680851 (-190 3135);
PAINT MONO (-190 3135);
FORCEPROP 0 LASTPIN (-200 1475) $PN 118
J 0
(-190 1485);
DISPLAY 0.680851 (-190 1485);
PAINT MONO (-190 1485);
FORCEPROP 0 LASTPIN (-200 3175) $PN 27
J 0
(-190 3185);
DISPLAY 0.680851 (-190 3185);
PAINT MONO (-190 3185);
FORCEPROP 0 LASTPIN (-200 1525) $PN 120
J 0
(-190 1535);
DISPLAY 0.680851 (-190 1535);
PAINT MONO (-190 1535);
FORCEPROP 0 LASTPIN (-200 3225) $PN 170
J 0
(-190 3235);
DISPLAY 0.680851 (-190 3235);
PAINT MONO (-190 3235);
FORCEPROP 0 LASTPIN (-200 1575) $PN 263
J 0
(-190 1585);
DISPLAY 0.680851 (-190 1585);
PAINT MONO (-190 1585);
FORCEPROP 0 LASTPIN (-200 3275) $PN 172
J 0
(-190 3285);
DISPLAY 0.680851 (-190 3285);
PAINT MONO (-190 3285);
FORCEPROP 0 LASTPIN (-200 1625) $PN 265
J 0
(-190 1635);
DISPLAY 0.680851 (-190 1635);
PAINT MONO (-190 1635);
FORCEPROP 0 LASTPIN (-200 3325) $PN 29
J 0
(-190 3335);
DISPLAY 0.680851 (-190 3335);
PAINT MONO (-190 3335);
FORCEPROP 0 LASTPIN (-200 1675) $PN 122
J 0
(-190 1685);
DISPLAY 0.680851 (-190 1685);
PAINT MONO (-190 1685);
FORCEPROP 0 LASTPIN (-200 3375) $PN 31
J 0
(-190 3385);
DISPLAY 0.680851 (-190 3385);
PAINT MONO (-190 3385);
FORCEPROP 0 LASTPIN (-200 1725) $PN 124
J 0
(-190 1735);
DISPLAY 0.680851 (-190 1735);
PAINT MONO (-190 1735);
FORCEPROP 0 LASTPIN (-200 3425) $PN 174
J 0
(-190 3435);
DISPLAY 0.680851 (-190 3435);
PAINT MONO (-190 3435);
FORCEPROP 0 LASTPIN (-200 1775) $PN 267
J 0
(-190 1785);
DISPLAY 0.680851 (-190 1785);
PAINT MONO (-190 1785);
FORCEPROP 0 LASTPIN (-200 3475) $PN 176
J 0
(-190 3485);
DISPLAY 0.680851 (-190 3485);
PAINT MONO (-190 3485);
FORCEPROP 0 LASTPIN (-200 1825) $PN 269
J 0
(-190 1835);
DISPLAY 0.680851 (-190 1835);
PAINT MONO (-190 1835);
FORCEPROP 0 LASTPIN (-200 3525) $PN 36
J 0
(-190 3535);
DISPLAY 0.680851 (-190 3535);
PAINT MONO (-190 3535);
FORCEPROP 0 LASTPIN (-200 1875) $PN 129
J 0
(-190 1885);
DISPLAY 0.680851 (-190 1885);
PAINT MONO (-190 1885);
FORCEPROP 0 LASTPIN (-200 3575) $PN 38
J 0
(-190 3585);
DISPLAY 0.680851 (-190 3585);
PAINT MONO (-190 3585);
FORCEPROP 0 LASTPIN (-200 1925) $PN 131
J 0
(-190 1935);
DISPLAY 0.680851 (-190 1935);
PAINT MONO (-190 1935);
FORCEPROP 0 LASTPIN (-200 3625) $PN 181
J 0
(-190 3635);
DISPLAY 0.680851 (-190 3635);
PAINT MONO (-190 3635);
FORCEPROP 0 LASTPIN (-200 1975) $PN 274
J 0
(-190 1985);
DISPLAY 0.680851 (-190 1985);
PAINT MONO (-190 1985);
FORCEPROP 0 LASTPIN (-200 3675) $PN 183
J 0
(-190 3685);
DISPLAY 0.680851 (-190 3685);
PAINT MONO (-190 3685);
FORCEPROP 0 LASTPIN (-200 2025) $PN 276
J 0
(-190 2035);
DISPLAY 0.680851 (-190 2035);
PAINT MONO (-190 2035);
FORCEPROP 0 LASTPIN (-200 3725) $PN 40
J 0
(-190 3735);
DISPLAY 0.680851 (-190 3735);
PAINT MONO (-190 3735);
FORCEPROP 0 LASTPIN (-200 2075) $PN 133
J 0
(-190 2085);
DISPLAY 0.680851 (-190 2085);
PAINT MONO (-190 2085);
FORCEPROP 0 LASTPIN (-200 3775) $PN 42
J 0
(-190 3785);
DISPLAY 0.680851 (-190 3785);
PAINT MONO (-190 3785);
FORCEPROP 0 LASTPIN (-200 2125) $PN 135
J 0
(-190 2135);
DISPLAY 0.680851 (-190 2135);
PAINT MONO (-190 2135);
FORCEPROP 0 LASTPIN (-200 3825) $PN 185
J 0
(-190 3835);
DISPLAY 0.680851 (-190 3835);
PAINT MONO (-190 3835);
FORCEPROP 0 LASTPIN (-200 2175) $PN 278
J 0
(-190 2185);
DISPLAY 0.680851 (-190 2185);
PAINT MONO (-190 2185);
FORCEPROP 0 LASTPIN (-200 3875) $PN 187
J 0
(-190 3885);
DISPLAY 0.680851 (-190 3885);
PAINT MONO (-190 3885);
FORCEPROP 0 LASTPIN (-200 2225) $PN 280
J 0
(-190 2235);
DISPLAY 0.680851 (-190 2235);
PAINT MONO (-190 2235);
FORCEPROP 0 LASTPIN (-200 3925) $PN 47
J 0
(-190 3935);
DISPLAY 0.680851 (-190 3935);
PAINT MONO (-190 3935);
FORCEPROP 0 LASTPIN (-200 2275) $PN 140
J 0
(-190 2285);
DISPLAY 0.680851 (-190 2285);
PAINT MONO (-190 2285);
FORCEPROP 0 LASTPIN (-200 3975) $PN 49
J 0
(-190 3985);
DISPLAY 0.680851 (-190 3985);
PAINT MONO (-190 3985);
FORCEPROP 0 LASTPIN (-200 2325) $PN 142
J 0
(-190 2335);
DISPLAY 0.680851 (-190 2335);
PAINT MONO (-190 2335);
FORCEPROP 0 LASTPIN (-200 4025) $PN 192
J 0
(-190 4035);
DISPLAY 0.680851 (-190 4035);
PAINT MONO (-190 4035);
FORCEPROP 0 LASTPIN (-200 2375) $PN 285
J 0
(-190 2385);
DISPLAY 0.680851 (-190 2385);
PAINT MONO (-190 2385);
FORCEPROP 0 LASTPIN (-200 4075) $PN 194
J 0
(-190 4085);
DISPLAY 0.680851 (-190 4085);
PAINT MONO (-190 4085);
FORCEPROP 0 LASTPIN (-200 2425) $PN 287
J 0
(-190 2435);
DISPLAY 0.680851 (-190 2435);
PAINT MONO (-190 2435);
FORCEPROP 0 LASTPIN (-1400 1575) $PN 148
J 2
(-1410 1585);
DISPLAY 0.680851 (-1410 1585);
PAINT MONO (-1410 1585);
FORCEPROP 0 LASTPIN (-1400 1475) $PN 4
J 2
(-1410 1485);
DISPLAY 0.680851 (-1410 1485);
PAINT MONO (-1410 1485);
FORCEPROP 0 LASTPIN (-1400 1525) $PN 5
J 2
(-1410 1535);
DISPLAY 0.680851 (-1410 1535);
PAINT MONO (-1410 1535);
FORCEPROP 0 LASTPIN (-1400 675) $PN 86
J 2
(-1410 685);
DISPLAY 0.680851 (-1410 685);
PAINT MONO (-1410 685);
FORCEPROP 0 LASTPIN (-1400 625) $PN 87
J 2
(-1410 635);
DISPLAY 0.680851 (-1410 635);
PAINT MONO (-1410 635);
FORCEPROP 0 LASTPIN (-1400 3275) $PN 74
J 2
(-1410 3285);
DISPLAY 0.680851 (-1410 3285);
PAINT MONO (-1410 3285);
FORCEPROP 0 LASTPIN (-1400 3225) $PN 227
J 2
(-1410 3235);
DISPLAY 0.680851 (-1410 3235);
PAINT MONO (-1410 3235);
FORCEPROP 0 LASTPIN (-1400 1225) $PN 147
J 2
(-1410 1235);
DISPLAY 0.680851 (-1410 1235);
PAINT MONO (-1410 1235);
FORCEPROP 0 LASTPIN (-1400 1775) $PN 207
J 2
(-1410 1785);
DISPLAY 0.680851 (-1410 1785);
PAINT MONO (-1410 1785);
FORCEPROP 0 LASTPIN (-1400 825) $PN 2
J 2
(-1410 835);
DISPLAY 0.680851 (-1410 835);
PAINT MONO (-1410 835);
FORCEPROP 0 LASTPIN (-1400 875) $PN 144
J 2
(-1410 885);
DISPLAY 0.680851 (-1410 885);
PAINT MONO (-1410 885);
FORCEPROP 0 LASTPIN (-1400 925) $PN 149
J 2
(-1410 935);
DISPLAY 0.680851 (-1410 935);
PAINT MONO (-1410 935);
FORCEPROP 0 LASTPIN (-1400 975) $PN 150
J 2
(-1410 985);
DISPLAY 0.680851 (-1410 985);
PAINT MONO (-1410 985);
FORCEPROP 0 LASTPIN (-1400 1025) $PN 220
J 2
(-1410 1035);
DISPLAY 0.680851 (-1410 1035);
PAINT MONO (-1410 1035);
FORCEPROP 0 LASTPIN (-1400 1075) $PN 231
J 2
(-1410 1085);
DISPLAY 0.680851 (-1410 1085);
PAINT MONO (-1410 1085);
FORCEPROP 0 LASTPIN (-1400 1125) $PN 232
J 2
(-1410 1135);
DISPLAY 0.680851 (-1410 1135);
PAINT MONO (-1410 1135);
FORCEPROP 0 LASTPIN (-1400 1625) $PN 3
J 2
(-1410 1635);
DISPLAY 0.680851 (-1410 1635);
PAINT MONO (-1410 1635);
FORCEPROP 1 LAST NEEDS_NO_SIZE TRUE
J 0
(-800 2350);
DISPLAY 0.723404 (-800 2350);
PAINT GREEN (-800 2350);
DISPLAY INVISIBLE (-800 2350);
FORCEPROP 1 LAST CDS_LMAN_SYM_OUTLINE -450,1875,450,-1875
J 0
(-800 2350);
DISPLAY 0.468085 (-800 2350);
PAINT GREEN (-800 2350);
DISPLAY INVISIBLE (-800 2350);
FORCEPROP 2 LAST CDS_LIB pure_quanta
J 0
(-800 2350);
DISPLAY INVISIBLE (-800 2350);
FORCEPROP 2 LAST CDS_LOCATION J17
J 0
(-1250 4575);
DISPLAY 1.021277 (-1250 4575);
DISPLAY INVISIBLE (-1250 4575);
FORCEPROP 0 LAST $SEC 1
J 0
(-1225 4575);
DISPLAY 0.680851 (-1225 4575);
PAINT MONO (-1225 4575);
DISPLAY INVISIBLE (-1225 4575);
FORCEPROP 2 LAST CDS_SEC 1
J 0
(-1250 4575);
DISPLAY 1.021277 (-1250 4575);
DISPLAY INVISIBLE (-1250 4575);
FORCEPROP 1 LAST PATH I12
J 0
(-800 2350);
DISPLAY 0.723404 (-800 2350);
PAINT GREEN (-800 2350);
DISPLAY INVISIBLE (-800 2350);
FORCEADD VCC_CORE..1
(1750 525);
FORCEPROP 3 LASTPIN (1750 475) SIG_NAME P3V3_AUX\g
J 0
(1760 485);
DISPLAY 0.659574 (1760 485);
PAINT MONO (1760 485);
DISPLAY INVISIBLE (1760 485);
FORCEPROP 1 LAST HDL_POWER P3V3_AUX
J 1
(1750 575);
DISPLAY 1.148936 (1750 575);
PAINT GREEN (1750 575);
FORCEPROP 2 LAST CDS_LIB logical_power
J 0
(1750 525);
PAINT MONO (1750 525);
DISPLAY INVISIBLE (1750 525);
FORCEPROP 1 LAST PATH I120
J 0
(1800 550);
DISPLAY 0.872340 (1800 550);
PAINT AQUA (1800 550);
DISPLAY INVISIBLE (1800 550);
FORCEADD UNIVERSAL_GND..1
(1750 -175);
FORCEPROP 3 LASTPIN (1750 -125) SIG_NAME GND\g
J 0
(1760 -115);
DISPLAY 0.659574 (1760 -115);
PAINT MONO (1760 -115);
DISPLAY INVISIBLE (1760 -115);
FORCEPROP 2 LAST CDS_LIB logical_power
J 0
(1750 -175);
PAINT MONO (1750 -175);
DISPLAY INVISIBLE (1750 -175);
FORCEPROP 1 LAST HDL_POWER GND
J 1
(1775 -250);
DISPLAY 0.872340 (1775 -250);
PAINT GREEN (1775 -250);
DISPLAY INVISIBLE (1775 -250);
FORCEPROP 1 LAST PATH I121
J 0
(1825 -175);
DISPLAY 0.872340 (1825 -175);
PAINT AQUA (1825 -175);
DISPLAY INVISIBLE (1825 -175);
FORCEADD Q_CAP..1
(1750 200);
FORCEPROP 1 LAST PART_NUMBER CH5221MEB00
J 0
(1800 50);
DISPLAY 0.978723 (1800 50);
DISPLAY INVISIBLE (1800 50);
FORCEPROP 1 LAST VALUE 2.2UF
J 0
(1800 250);
DISPLAY 0.978723 (1800 250);
FORCEPROP 1 LAST MATERIAL X6S
J 0
(1800 100);
DISPLAY 0.978723 (1800 100);
FORCEPROP 1 LAST VOLTAGE 6.3V
J 0
(1800 200);
DISPLAY 0.978723 (1800 200);
FORCEPROP 1 LAST TOLERANCE 20%
J 0
(1800 150);
DISPLAY 0.978723 (1800 150);
FORCEPROP 1 LAST PACK_TYPE C0402
J 0
(1800 0);
DISPLAY 0.978723 (1800 0);
FORCEPROP 1 LAST $LOCATION C50
J 0
(1800 300);
DISPLAY 0.978723 (1800 300);
FORCEPROP 1 LASTPIN (1750 300) $PN 1
J 0
(1760 280);
DISPLAY 0.787234 (1760 280);
FORCEPROP 1 LASTPIN (1750 100) $PN 2
J 0
(1760 80);
DISPLAY 0.787234 (1760 80);
FORCEPROP 2 LAST CDS_LIB pure_quanta
J 0
(1750 200);
PAINT MONO (1750 200);
DISPLAY INVISIBLE (1750 200);
FORCEPROP 2 LAST CDS_LOCATION C50
J 0
(1800 400);
DISPLAY 1.021277 (1800 400);
DISPLAY INVISIBLE (1800 400);
FORCEPROP 2 LAST $SEC 1
J 0
(1800 400);
DISPLAY 0.680851 (1800 400);
PAINT MONO (1800 400);
DISPLAY INVISIBLE (1800 400);
FORCEPROP 2 LAST CDS_SEC 1
J 0
(1800 400);
DISPLAY 1.021277 (1800 400);
DISPLAY INVISIBLE (1800 400);
FORCEPROP 1 LAST PATH I122
J 0
(1800 350);
DISPLAY 0.978723 (1800 350);
PAINT WHITE (1800 350);
DISPLAY INVISIBLE (1800 350);
FORCEADD Q_CAP..1
(2750 200);
FORCEPROP 1 LAST PART_NUMBER CH6103KEA00
J 0
(2800 50);
DISPLAY 0.978723 (2800 50);
DISPLAY INVISIBLE (2800 50);
FORCEPROP 1 LAST PACK_TYPE C0805
J 0
(2800 0);
DISPLAY 0.978723 (2800 0);
FORCEPROP 1 LAST TOLERANCE 10%
J 0
(2800 150);
DISPLAY 0.978723 (2800 150);
FORCEPROP 1 LAST VALUE 10UF
J 0
(2800 250);
DISPLAY 0.978723 (2800 250);
FORCEPROP 1 LAST VOLTAGE 16V
J 0
(2800 200);
DISPLAY 0.978723 (2800 200);
FORCEPROP 1 LAST MATERIAL X6S
J 0
(2800 100);
DISPLAY 0.978723 (2800 100);
FORCEPROP 1 LAST $LOCATION C51
J 0
(2800 300);
DISPLAY 0.978723 (2800 300);
FORCEPROP 1 LASTPIN (2750 300) $PN 1
J 0
(2760 280);
DISPLAY 0.787234 (2760 280);
FORCEPROP 1 LASTPIN (2750 100) $PN 2
J 0
(2760 80);
DISPLAY 0.787234 (2760 80);
FORCEPROP 2 LAST CDS_LIB pure_quanta
J 0
(2750 200);
PAINT MONO (2750 200);
DISPLAY INVISIBLE (2750 200);
FORCEPROP 2 LAST CDS_LOCATION C51
J 0
(2800 400);
DISPLAY 1.021277 (2800 400);
DISPLAY INVISIBLE (2800 400);
FORCEPROP 2 LAST $SEC 1
J 0
(2800 400);
DISPLAY 0.680851 (2800 400);
PAINT MONO (2800 400);
DISPLAY INVISIBLE (2800 400);
FORCEPROP 2 LAST CDS_SEC 1
J 0
(2800 400);
DISPLAY 1.021277 (2800 400);
DISPLAY INVISIBLE (2800 400);
FORCEPROP 1 LAST PATH I123
J 0
(2800 350);
DISPLAY 0.978723 (2800 350);
PAINT WHITE (2800 350);
DISPLAY INVISIBLE (2800 350);
FORCEADD VCC_CORE..1
(2750 525);
FORCEPROP 3 LASTPIN (2750 475) SIG_NAME P12V_S3_AUX_CPU1_NVDIMM\g
J 0
(2760 485);
DISPLAY 0.659574 (2760 485);
PAINT MONO (2760 485);
DISPLAY INVISIBLE (2760 485);
FORCEPROP 1 LAST HDL_POWER P12V_S3_AUX_CPU1_NVDIMM
J 1
(2750 575);
DISPLAY 1.148936 (2750 575);
PAINT GREEN (2750 575);
FORCEPROP 2 LAST CDS_LIB logical_power
J 0
(2750 525);
PAINT MONO (2750 525);
DISPLAY INVISIBLE (2750 525);
FORCEPROP 1 LAST PATH I124
J 0
(2800 550);
DISPLAY 0.872340 (2800 550);
PAINT AQUA (2800 550);
DISPLAY INVISIBLE (2800 550);
FORCEADD OFFPAGE..3
(850 2450);
FORCEPROP 2 LAST $XR1 99 
J 0
(1154 2450);
DISPLAY 0.638298 (1154 2450);
PAINT MONO (1154 2450);
FORCEPROP 2 LAST $XR0 51 
J 0
(1064 2450);
DISPLAY 0.638298 (1064 2450);
PAINT MONO (1064 2450);
FORCEPROP 2 LAST CDS_LIB standard
J 2
(850 2450);
DISPLAY INVISIBLE (850 2450);
FORCEPROP 1 LAST OFFPAGE TRUE
J 0
(1175 2325);
DISPLAY 0.872340 (1175 2325);
DISPLAY INVISIBLE (1175 2325);
FORCEPROP 1 LAST COMMENT_BODY TRUE
J 0
(800 2350);
DISPLAY 0.872340 (800 2350);
PAINT GREEN (800 2350);
DISPLAY INVISIBLE (800 2350);
FORCEPROP 2 LAST PATH I125
J 0
(1050 2525);
DISPLAY 1.021277 (1050 2525);
DISPLAY INVISIBLE (1050 2525);
FORCEADD TAP..1
(2775 2125);
FORCEPROP 3 LASTPIN (2725 2125) SIG_NAME M_A_CPU1_SB_DQS_DP<0>
J 0
(2735 2135);
DISPLAY 0.659574 (2735 2135);
PAINT MONO (2735 2135);
DISPLAY INVISIBLE (2735 2135);
FORCEPROP 1 LASTPIN (2725 2125) BN 0
J 0
(2713 2133);
DISPLAY 0.680851 (2713 2133);
PAINT GREEN (2713 2133);
FORCEPROP 2 LAST CDS_LIB standard
J 0
(2775 2125);
PAINT MONO (2775 2125);
DISPLAY INVISIBLE (2775 2125);
FORCEPROP 1 LAST BODY_TYPE PLUMBING
J 0
(2775 2175);
DISPLAY 0.872340 (2775 2175);
PAINT GREEN (2775 2175);
DISPLAY INVISIBLE (2775 2175);
FORCEPROP 1 LAST HDL_TAP TRUE
J 0
(3100 2000);
DISPLAY 0.872340 (3100 2000);
DISPLAY INVISIBLE (3100 2000);
FORCEPROP 1 LAST PATH I127
J 0
(2773 2125);
DISPLAY 0.872340 (2773 2125);
PAINT GREEN (2773 2125);
DISPLAY INVISIBLE (2773 2125);
FORCEADD TAP..1
(2775 2325);
FORCEPROP 3 LASTPIN (2725 2325) SIG_NAME M_A_CPU1_SB_DQS_DP<2>
J 0
(2735 2335);
DISPLAY 0.659574 (2735 2335);
PAINT MONO (2735 2335);
DISPLAY INVISIBLE (2735 2335);
FORCEPROP 1 LASTPIN (2725 2325) BN 2
J 0
(2713 2333);
DISPLAY 0.680851 (2713 2333);
PAINT GREEN (2713 2333);
FORCEPROP 2 LAST CDS_LIB standard
J 0
(2775 2325);
DISPLAY INVISIBLE (2775 2325);
FORCEPROP 1 LAST BODY_TYPE PLUMBING
J 0
(2775 2375);
DISPLAY 0.872340 (2775 2375);
PAINT GREEN (2775 2375);
DISPLAY INVISIBLE (2775 2375);
FORCEPROP 1 LAST HDL_TAP TRUE
J 0
(3100 2200);
DISPLAY 0.872340 (3100 2200);
DISPLAY INVISIBLE (3100 2200);
FORCEPROP 1 LAST PATH I128
J 0
(2773 2325);
DISPLAY 0.872340 (2773 2325);
PAINT GREEN (2773 2325);
DISPLAY INVISIBLE (2773 2325);
FORCEADD TAP..1
(2775 2225);
FORCEPROP 3 LASTPIN (2725 2225) SIG_NAME M_A_CPU1_SB_DQS_DP<1>
J 0
(2735 2235);
DISPLAY 0.659574 (2735 2235);
PAINT MONO (2735 2235);
DISPLAY INVISIBLE (2735 2235);
FORCEPROP 1 LASTPIN (2725 2225) BN 1
J 0
(2713 2233);
DISPLAY 0.680851 (2713 2233);
PAINT GREEN (2713 2233);
FORCEPROP 2 LAST CDS_LIB standard
J 0
(2775 2225);
DISPLAY INVISIBLE (2775 2225);
FORCEPROP 1 LAST BODY_TYPE PLUMBING
J 0
(2775 2275);
DISPLAY 0.872340 (2775 2275);
PAINT GREEN (2775 2275);
DISPLAY INVISIBLE (2775 2275);
FORCEPROP 1 LAST HDL_TAP TRUE
J 0
(3100 2100);
DISPLAY 0.872340 (3100 2100);
DISPLAY INVISIBLE (3100 2100);
FORCEPROP 1 LAST PATH I129
J 0
(2773 2225);
DISPLAY 0.872340 (2773 2225);
PAINT GREEN (2773 2225);
DISPLAY INVISIBLE (2773 2225);
FORCEADD OFFPAGE..3
R 2
(-2550 2250);
FORCEPROP 2 LAST $XR1 99 
J 0
(-2889 2250);
DISPLAY 0.638298 (-2889 2250);
PAINT MONO (-2889 2250);
FORCEPROP 2 LAST $XR0 51 
J 0
(-2799 2250);
DISPLAY 0.638298 (-2799 2250);
PAINT MONO (-2799 2250);
FORCEPROP 2 LAST CDS_LIB standard
J 0
(-2550 2250);
PAINT MONO (-2550 2250);
DISPLAY INVISIBLE (-2550 2250);
FORCEPROP 1 LAST OFFPAGE TRUE
J 2
(-2875 2125);
DISPLAY 0.872340 (-2875 2125);
DISPLAY INVISIBLE (-2875 2125);
FORCEPROP 1 LAST COMMENT_BODY TRUE
J 2
(-2500 2150);
DISPLAY 0.872340 (-2500 2150);
PAINT GREEN (-2500 2150);
DISPLAY INVISIBLE (-2500 2150);
FORCEPROP 2 LAST PATH I13
J 0
(-2500 2325);
DISPLAY 1.021277 (-2500 2325);
DISPLAY INVISIBLE (-2500 2325);
FORCEADD TAP..1
(2775 2425);
FORCEPROP 3 LASTPIN (2725 2425) SIG_NAME M_A_CPU1_SB_DQS_DP<3>
J 0
(2735 2435);
DISPLAY 0.659574 (2735 2435);
PAINT MONO (2735 2435);
DISPLAY INVISIBLE (2735 2435);
FORCEPROP 1 LASTPIN (2725 2425) BN 3
J 0
(2713 2433);
DISPLAY 0.680851 (2713 2433);
PAINT GREEN (2713 2433);
FORCEPROP 2 LAST CDS_LIB standard
J 0
(2775 2425);
PAINT MONO (2775 2425);
DISPLAY INVISIBLE (2775 2425);
FORCEPROP 1 LAST BODY_TYPE PLUMBING
J 0
(2775 2475);
DISPLAY 0.872340 (2775 2475);
PAINT GREEN (2775 2475);
DISPLAY INVISIBLE (2775 2475);
FORCEPROP 1 LAST HDL_TAP TRUE
J 0
(3100 2300);
DISPLAY 0.872340 (3100 2300);
DISPLAY INVISIBLE (3100 2300);
FORCEPROP 1 LAST PATH I130
J 0
(2773 2425);
DISPLAY 0.872340 (2773 2425);
PAINT GREEN (2773 2425);
DISPLAY INVISIBLE (2773 2425);
FORCEADD TAP..1
(2775 2525);
FORCEPROP 3 LASTPIN (2725 2525) SIG_NAME M_A_CPU1_SB_DQS_DP<4>
J 0
(2735 2535);
DISPLAY 0.659574 (2735 2535);
PAINT MONO (2735 2535);
DISPLAY INVISIBLE (2735 2535);
FORCEPROP 1 LASTPIN (2725 2525) BN 4
J 0
(2713 2533);
DISPLAY 0.680851 (2713 2533);
PAINT GREEN (2713 2533);
FORCEPROP 2 LAST CDS_LIB standard
J 0
(2775 2525);
PAINT MONO (2775 2525);
DISPLAY INVISIBLE (2775 2525);
FORCEPROP 1 LAST BODY_TYPE PLUMBING
J 0
(2775 2575);
DISPLAY 0.872340 (2775 2575);
PAINT GREEN (2775 2575);
DISPLAY INVISIBLE (2775 2575);
FORCEPROP 1 LAST HDL_TAP TRUE
J 0
(3100 2400);
DISPLAY 0.872340 (3100 2400);
DISPLAY INVISIBLE (3100 2400);
FORCEPROP 1 LAST PATH I131
J 0
(2773 2525);
DISPLAY 0.872340 (2773 2525);
PAINT GREEN (2773 2525);
DISPLAY INVISIBLE (2773 2525);
FORCEADD TAP..1
(2775 2625);
FORCEPROP 3 LASTPIN (2725 2625) SIG_NAME M_A_CPU1_SB_DQS_DP<5>
J 0
(2735 2635);
DISPLAY 0.659574 (2735 2635);
PAINT MONO (2735 2635);
DISPLAY INVISIBLE (2735 2635);
FORCEPROP 1 LASTPIN (2725 2625) BN 5
J 0
(2713 2633);
DISPLAY 0.680851 (2713 2633);
PAINT GREEN (2713 2633);
FORCEPROP 2 LAST CDS_LIB standard
J 0
(2775 2625);
DISPLAY INVISIBLE (2775 2625);
FORCEPROP 1 LAST BODY_TYPE PLUMBING
J 0
(2775 2675);
DISPLAY 0.872340 (2775 2675);
PAINT GREEN (2775 2675);
DISPLAY INVISIBLE (2775 2675);
FORCEPROP 1 LAST HDL_TAP TRUE
J 0
(3100 2500);
DISPLAY 0.872340 (3100 2500);
DISPLAY INVISIBLE (3100 2500);
FORCEPROP 1 LAST PATH I132
J 0
(2773 2625);
DISPLAY 0.872340 (2773 2625);
PAINT GREEN (2773 2625);
DISPLAY INVISIBLE (2773 2625);
FORCEADD TAP..1
(2775 2825);
FORCEPROP 3 LASTPIN (2725 2825) SIG_NAME M_A_CPU1_SB_DQS_DP<7>
J 0
(2735 2835);
DISPLAY 0.659574 (2735 2835);
PAINT MONO (2735 2835);
DISPLAY INVISIBLE (2735 2835);
FORCEPROP 1 LASTPIN (2725 2825) BN 7
J 0
(2713 2833);
DISPLAY 0.680851 (2713 2833);
PAINT GREEN (2713 2833);
FORCEPROP 2 LAST CDS_LIB standard
J 0
(2775 2825);
DISPLAY INVISIBLE (2775 2825);
FORCEPROP 1 LAST BODY_TYPE PLUMBING
J 0
(2775 2875);
DISPLAY 0.872340 (2775 2875);
PAINT GREEN (2775 2875);
DISPLAY INVISIBLE (2775 2875);
FORCEPROP 1 LAST HDL_TAP TRUE
J 0
(3100 2700);
DISPLAY 0.872340 (3100 2700);
DISPLAY INVISIBLE (3100 2700);
FORCEPROP 1 LAST PATH I133
J 0
(2773 2825);
DISPLAY 0.872340 (2773 2825);
PAINT GREEN (2773 2825);
DISPLAY INVISIBLE (2773 2825);
FORCEADD TAP..1
(2775 2725);
FORCEPROP 3 LASTPIN (2725 2725) SIG_NAME M_A_CPU1_SB_DQS_DP<6>
J 0
(2735 2735);
DISPLAY 0.659574 (2735 2735);
PAINT MONO (2735 2735);
DISPLAY INVISIBLE (2735 2735);
FORCEPROP 1 LASTPIN (2725 2725) BN 6
J 0
(2713 2733);
DISPLAY 0.680851 (2713 2733);
PAINT GREEN (2713 2733);
FORCEPROP 2 LAST CDS_LIB standard
J 0
(2775 2725);
DISPLAY INVISIBLE (2775 2725);
FORCEPROP 1 LAST BODY_TYPE PLUMBING
J 0
(2775 2775);
DISPLAY 0.872340 (2775 2775);
PAINT GREEN (2775 2775);
DISPLAY INVISIBLE (2775 2775);
FORCEPROP 1 LAST HDL_TAP TRUE
J 0
(3100 2600);
DISPLAY 0.872340 (3100 2600);
DISPLAY INVISIBLE (3100 2600);
FORCEPROP 1 LAST PATH I134
J 0
(2773 2725);
DISPLAY 0.872340 (2773 2725);
PAINT GREEN (2773 2725);
DISPLAY INVISIBLE (2773 2725);
FORCEADD TAP..1
(2775 2925);
FORCEPROP 3 LASTPIN (2725 2925) SIG_NAME M_A_CPU1_SB_DQS_DP<8>
J 0
(2735 2935);
DISPLAY 0.659574 (2735 2935);
PAINT MONO (2735 2935);
DISPLAY INVISIBLE (2735 2935);
FORCEPROP 1 LASTPIN (2725 2925) BN 8
J 0
(2713 2933);
DISPLAY 0.680851 (2713 2933);
PAINT GREEN (2713 2933);
FORCEPROP 2 LAST CDS_LIB standard
J 0
(2775 2925);
DISPLAY INVISIBLE (2775 2925);
FORCEPROP 1 LAST BODY_TYPE PLUMBING
J 0
(2775 2975);
DISPLAY 0.872340 (2775 2975);
PAINT GREEN (2775 2975);
DISPLAY INVISIBLE (2775 2975);
FORCEPROP 1 LAST HDL_TAP TRUE
J 0
(3100 2800);
DISPLAY 0.872340 (3100 2800);
DISPLAY INVISIBLE (3100 2800);
FORCEPROP 1 LAST PATH I135
J 0
(2773 2925);
DISPLAY 0.872340 (2773 2925);
PAINT GREEN (2773 2925);
DISPLAY INVISIBLE (2773 2925);
FORCEADD TAP..1
(2775 3025);
FORCEPROP 3 LASTPIN (2725 3025) SIG_NAME M_A_CPU1_SB_DQS_DP<9>
J 0
(2735 3035);
DISPLAY 0.659574 (2735 3035);
PAINT MONO (2735 3035);
DISPLAY INVISIBLE (2735 3035);
FORCEPROP 1 LASTPIN (2725 3025) BN 9
J 0
(2713 3033);
DISPLAY 0.680851 (2713 3033);
PAINT GREEN (2713 3033);
FORCEPROP 2 LAST CDS_LIB standard
J 0
(2775 3025);
DISPLAY INVISIBLE (2775 3025);
FORCEPROP 1 LAST BODY_TYPE PLUMBING
J 0
(2775 3075);
DISPLAY 0.872340 (2775 3075);
PAINT GREEN (2775 3075);
DISPLAY INVISIBLE (2775 3075);
FORCEPROP 1 LAST HDL_TAP TRUE
J 0
(3100 2900);
DISPLAY 0.872340 (3100 2900);
DISPLAY INVISIBLE (3100 2900);
FORCEPROP 1 LAST PATH I136
J 0
(2773 3025);
DISPLAY 0.872340 (2773 3025);
PAINT GREEN (2773 3025);
DISPLAY INVISIBLE (2773 3025);
FORCEADD TAP..1
(2775 3175);
FORCEPROP 3 LASTPIN (2725 3175) SIG_NAME M_A_CPU1_SA_DQS_DP<0>
J 0
(2735 3185);
DISPLAY 0.659574 (2735 3185);
PAINT MONO (2735 3185);
DISPLAY INVISIBLE (2735 3185);
FORCEPROP 1 LASTPIN (2725 3175) BN 0
J 0
(2713 3183);
DISPLAY 0.680851 (2713 3183);
PAINT GREEN (2713 3183);
FORCEPROP 2 LAST CDS_LIB standard
J 0
(2775 3175);
PAINT MONO (2775 3175);
DISPLAY INVISIBLE (2775 3175);
FORCEPROP 1 LAST BODY_TYPE PLUMBING
J 0
(2775 3225);
DISPLAY 0.872340 (2775 3225);
PAINT GREEN (2775 3225);
DISPLAY INVISIBLE (2775 3225);
FORCEPROP 1 LAST HDL_TAP TRUE
J 0
(3100 3050);
DISPLAY 0.872340 (3100 3050);
DISPLAY INVISIBLE (3100 3050);
FORCEPROP 1 LAST PATH I137
J 0
(2773 3175);
DISPLAY 0.872340 (2773 3175);
PAINT GREEN (2773 3175);
DISPLAY INVISIBLE (2773 3175);
FORCEADD TAP..1
(2775 3275);
FORCEPROP 3 LASTPIN (2725 3275) SIG_NAME M_A_CPU1_SA_DQS_DP<1>
J 0
(2735 3285);
DISPLAY 0.659574 (2735 3285);
PAINT MONO (2735 3285);
DISPLAY INVISIBLE (2735 3285);
FORCEPROP 1 LASTPIN (2725 3275) BN 1
J 0
(2713 3283);
DISPLAY 0.680851 (2713 3283);
PAINT GREEN (2713 3283);
FORCEPROP 2 LAST CDS_LIB standard
J 0
(2775 3275);
DISPLAY INVISIBLE (2775 3275);
FORCEPROP 1 LAST BODY_TYPE PLUMBING
J 0
(2775 3325);
DISPLAY 0.872340 (2775 3325);
PAINT GREEN (2775 3325);
DISPLAY INVISIBLE (2775 3325);
FORCEPROP 1 LAST HDL_TAP TRUE
J 0
(3100 3150);
DISPLAY 0.872340 (3100 3150);
DISPLAY INVISIBLE (3100 3150);
FORCEPROP 1 LAST PATH I138
J 0
(2773 3275);
DISPLAY 0.872340 (2773 3275);
PAINT GREEN (2773 3275);
DISPLAY INVISIBLE (2773 3275);
FORCEADD TAP..1
(2775 3375);
FORCEPROP 3 LASTPIN (2725 3375) SIG_NAME M_A_CPU1_SA_DQS_DP<2>
J 0
(2735 3385);
DISPLAY 0.659574 (2735 3385);
PAINT MONO (2735 3385);
DISPLAY INVISIBLE (2735 3385);
FORCEPROP 1 LASTPIN (2725 3375) BN 2
J 0
(2713 3383);
DISPLAY 0.680851 (2713 3383);
PAINT GREEN (2713 3383);
FORCEPROP 2 LAST CDS_LIB standard
J 0
(2775 3375);
DISPLAY INVISIBLE (2775 3375);
FORCEPROP 1 LAST BODY_TYPE PLUMBING
J 0
(2775 3425);
DISPLAY 0.872340 (2775 3425);
PAINT GREEN (2775 3425);
DISPLAY INVISIBLE (2775 3425);
FORCEPROP 1 LAST HDL_TAP TRUE
J 0
(3100 3250);
DISPLAY 0.872340 (3100 3250);
DISPLAY INVISIBLE (3100 3250);
FORCEPROP 1 LAST PATH I139
J 0
(2773 3375);
DISPLAY 0.872340 (2773 3375);
PAINT GREEN (2773 3375);
DISPLAY INVISIBLE (2773 3375);
FORCEADD VCC_CORE..1
(-2450 1950);
FORCEPROP 3 LASTPIN (-2450 1900) SIG_NAME P3V3_AUX\g
J 0
(-2440 1910);
DISPLAY 0.659574 (-2440 1910);
PAINT MONO (-2440 1910);
DISPLAY INVISIBLE (-2440 1910);
FORCEPROP 1 LAST HDL_POWER P3V3_AUX
J 1
(-2450 2000);
DISPLAY 1.148936 (-2450 2000);
PAINT GREEN (-2450 2000);
FORCEPROP 2 LAST CDS_LIB logical_power
J 0
(-2450 1950);
PAINT MONO (-2450 1950);
DISPLAY INVISIBLE (-2450 1950);
FORCEPROP 1 LAST PATH I14
J 0
(-2400 1975);
DISPLAY 0.872340 (-2400 1975);
PAINT AQUA (-2400 1975);
DISPLAY INVISIBLE (-2400 1975);
FORCEADD TAP..1
(2775 3475);
FORCEPROP 3 LASTPIN (2725 3475) SIG_NAME M_A_CPU1_SA_DQS_DP<3>
J 0
(2735 3485);
DISPLAY 0.659574 (2735 3485);
PAINT MONO (2735 3485);
DISPLAY INVISIBLE (2735 3485);
FORCEPROP 1 LASTPIN (2725 3475) BN 3
J 0
(2713 3483);
DISPLAY 0.680851 (2713 3483);
PAINT GREEN (2713 3483);
FORCEPROP 2 LAST CDS_LIB standard
J 0
(2775 3475);
PAINT MONO (2775 3475);
DISPLAY INVISIBLE (2775 3475);
FORCEPROP 1 LAST BODY_TYPE PLUMBING
J 0
(2775 3525);
DISPLAY 0.872340 (2775 3525);
PAINT GREEN (2775 3525);
DISPLAY INVISIBLE (2775 3525);
FORCEPROP 1 LAST HDL_TAP TRUE
J 0
(3100 3350);
DISPLAY 0.872340 (3100 3350);
DISPLAY INVISIBLE (3100 3350);
FORCEPROP 1 LAST PATH I140
J 0
(2773 3475);
DISPLAY 0.872340 (2773 3475);
PAINT GREEN (2773 3475);
DISPLAY INVISIBLE (2773 3475);
FORCEADD TAP..1
(2775 3575);
FORCEPROP 3 LASTPIN (2725 3575) SIG_NAME M_A_CPU1_SA_DQS_DP<4>
J 0
(2735 3585);
DISPLAY 0.659574 (2735 3585);
PAINT MONO (2735 3585);
DISPLAY INVISIBLE (2735 3585);
FORCEPROP 1 LASTPIN (2725 3575) BN 4
J 0
(2713 3583);
DISPLAY 0.680851 (2713 3583);
PAINT GREEN (2713 3583);
FORCEPROP 2 LAST CDS_LIB standard
J 0
(2775 3575);
PAINT MONO (2775 3575);
DISPLAY INVISIBLE (2775 3575);
FORCEPROP 1 LAST BODY_TYPE PLUMBING
J 0
(2775 3625);
DISPLAY 0.872340 (2775 3625);
PAINT GREEN (2775 3625);
DISPLAY INVISIBLE (2775 3625);
FORCEPROP 1 LAST HDL_TAP TRUE
J 0
(3100 3450);
DISPLAY 0.872340 (3100 3450);
DISPLAY INVISIBLE (3100 3450);
FORCEPROP 1 LAST PATH I141
J 0
(2773 3575);
DISPLAY 0.872340 (2773 3575);
PAINT GREEN (2773 3575);
DISPLAY INVISIBLE (2773 3575);
FORCEADD TAP..1
(2775 3675);
FORCEPROP 3 LASTPIN (2725 3675) SIG_NAME M_A_CPU1_SA_DQS_DP<5>
J 0
(2735 3685);
DISPLAY 0.659574 (2735 3685);
PAINT MONO (2735 3685);
DISPLAY INVISIBLE (2735 3685);
FORCEPROP 1 LASTPIN (2725 3675) BN 5
J 0
(2713 3683);
DISPLAY 0.680851 (2713 3683);
PAINT GREEN (2713 3683);
FORCEPROP 2 LAST CDS_LIB standard
J 0
(2775 3675);
DISPLAY INVISIBLE (2775 3675);
FORCEPROP 1 LAST BODY_TYPE PLUMBING
J 0
(2775 3725);
DISPLAY 0.872340 (2775 3725);
PAINT GREEN (2775 3725);
DISPLAY INVISIBLE (2775 3725);
FORCEPROP 1 LAST HDL_TAP TRUE
J 0
(3100 3550);
DISPLAY 0.872340 (3100 3550);
DISPLAY INVISIBLE (3100 3550);
FORCEPROP 1 LAST PATH I142
J 0
(2773 3675);
DISPLAY 0.872340 (2773 3675);
PAINT GREEN (2773 3675);
DISPLAY INVISIBLE (2773 3675);
FORCEADD TAP..1
(2775 3775);
FORCEPROP 3 LASTPIN (2725 3775) SIG_NAME M_A_CPU1_SA_DQS_DP<6>
J 0
(2735 3785);
DISPLAY 0.659574 (2735 3785);
PAINT MONO (2735 3785);
DISPLAY INVISIBLE (2735 3785);
FORCEPROP 1 LASTPIN (2725 3775) BN 6
J 0
(2713 3783);
DISPLAY 0.680851 (2713 3783);
PAINT GREEN (2713 3783);
FORCEPROP 2 LAST CDS_LIB standard
J 0
(2775 3775);
DISPLAY INVISIBLE (2775 3775);
FORCEPROP 1 LAST BODY_TYPE PLUMBING
J 0
(2775 3825);
DISPLAY 0.872340 (2775 3825);
PAINT GREEN (2775 3825);
DISPLAY INVISIBLE (2775 3825);
FORCEPROP 1 LAST HDL_TAP TRUE
J 0
(3100 3650);
DISPLAY 0.872340 (3100 3650);
DISPLAY INVISIBLE (3100 3650);
FORCEPROP 1 LAST PATH I143
J 0
(2773 3775);
DISPLAY 0.872340 (2773 3775);
PAINT GREEN (2773 3775);
DISPLAY INVISIBLE (2773 3775);
FORCEADD UNIVERSAL_GND..1
(3375 -175);
FORCEPROP 3 LASTPIN (3375 -125) SIG_NAME GND\g
J 0
(3385 -115);
DISPLAY 0.659574 (3385 -115);
PAINT MONO (3385 -115);
DISPLAY INVISIBLE (3385 -115);
FORCEPROP 2 LAST CDS_LIB logical_power
J 0
(3375 -175);
PAINT MONO (3375 -175);
DISPLAY INVISIBLE (3375 -175);
FORCEPROP 1 LAST HDL_POWER GND
J 1
(3400 -250);
DISPLAY 0.872340 (3400 -250);
PAINT GREEN (3400 -250);
DISPLAY INVISIBLE (3400 -250);
FORCEPROP 1 LAST PATH I144
J 0
(3450 -175);
DISPLAY 0.872340 (3450 -175);
PAINT AQUA (3450 -175);
DISPLAY INVISIBLE (3450 -175);
FORCEADD Q_CAP..1
(3375 200);
FORCEPROP 1 LAST PART_NUMBER CH6103KEA00
J 0
(3425 50);
DISPLAY 0.978723 (3425 50);
DISPLAY INVISIBLE (3425 50);
FORCEPROP 1 LAST TOLERANCE 10%
J 0
(3425 150);
DISPLAY 0.978723 (3425 150);
FORCEPROP 1 LAST VOLTAGE 16V
J 0
(3425 200);
DISPLAY 0.978723 (3425 200);
FORCEPROP 1 LAST VALUE 10UF
J 0
(3425 250);
DISPLAY 0.978723 (3425 250);
FORCEPROP 1 LAST PACK_TYPE C0805
J 0
(3425 0);
DISPLAY 0.978723 (3425 0);
FORCEPROP 1 LAST MATERIAL X6S
J 0
(3425 100);
DISPLAY 0.978723 (3425 100);
FORCEPROP 1 LAST $LOCATION C52
J 0
(3425 300);
DISPLAY 0.978723 (3425 300);
FORCEPROP 1 LASTPIN (3375 300) $PN 1
J 0
(3385 280);
DISPLAY 0.787234 (3385 280);
FORCEPROP 1 LASTPIN (3375 100) $PN 2
J 0
(3385 80);
DISPLAY 0.787234 (3385 80);
FORCEPROP 2 LAST CDS_LIB pure_quanta
J 0
(3375 200);
PAINT MONO (3375 200);
DISPLAY INVISIBLE (3375 200);
FORCEPROP 2 LAST CDS_LOCATION C52
J 0
(3425 400);
DISPLAY 1.021277 (3425 400);
DISPLAY INVISIBLE (3425 400);
FORCEPROP 2 LAST $SEC 1
J 0
(3425 400);
DISPLAY 0.680851 (3425 400);
PAINT MONO (3425 400);
DISPLAY INVISIBLE (3425 400);
FORCEPROP 2 LAST CDS_SEC 1
J 0
(3425 400);
DISPLAY 1.021277 (3425 400);
DISPLAY INVISIBLE (3425 400);
FORCEPROP 1 LAST PATH I145
J 0
(3425 350);
DISPLAY 0.978723 (3425 350);
PAINT WHITE (3425 350);
DISPLAY INVISIBLE (3425 350);
FORCEADD UNIVERSAL_GND..1
(4450 375);
FORCEPROP 3 LASTPIN (4450 425) SIG_NAME GND\g
J 0
(4460 435);
DISPLAY 0.659574 (4460 435);
PAINT MONO (4460 435);
DISPLAY INVISIBLE (4460 435);
FORCEPROP 2 LAST CDS_LIB logical_power
J 0
(4450 375);
PAINT MONO (4450 375);
DISPLAY INVISIBLE (4450 375);
FORCEPROP 1 LAST HDL_POWER GND
J 1
(4475 300);
DISPLAY 0.872340 (4475 300);
PAINT GREEN (4475 300);
DISPLAY INVISIBLE (4475 300);
FORCEPROP 1 LAST PATH I146
J 0
(4525 375);
DISPLAY 0.872340 (4525 375);
PAINT AQUA (4525 375);
DISPLAY INVISIBLE (4525 375);
FORCEADD SCONN288_ADR50017P130CC..3
(5300 2450);
FORCEPROP 1 LAST PART_NUMBER DFHST8FS461
J 0
(4845 4374);
DISPLAY 0.723404 (4845 4374);
PAINT GREEN (4845 4374);
DISPLAY INVISIBLE (4845 4374);
FORCEPROP 1 LAST MATERIAL IO
J 0
(4845 4247);
DISPLAY 0.723404 (4845 4247);
PAINT GREEN (4845 4247);
FORCEPROP 2 LAST VALUE SCONN288_ADR50017-P130CC
J 0
(4850 4475);
DISPLAY 1.021277 (4850 4475);
FORCEPROP 2 LAST PART_TYPE SMLF
J 0
(4850 4525);
DISPLAY 1.021277 (4850 4525);
FORCEPROP 1 LAST $LOCATION J17
J 0
(4850 4425);
DISPLAY 0.723404 (4850 4425);
PAINT GREEN (4850 4425);
FORCEPROP 0 LASTPIN (5900 825) $PN G1
J 0
(5910 835);
DISPLAY 0.680851 (5910 835);
PAINT MONO (5910 835);
FORCEPROP 0 LASTPIN (5900 775) $PN G2
J 0
(5910 785);
DISPLAY 0.680851 (5910 785);
PAINT MONO (5910 785);
FORCEPROP 0 LASTPIN (5900 725) $PN G3
J 0
(5910 735);
DISPLAY 0.680851 (5910 735);
PAINT MONO (5910 735);
FORCEPROP 0 LASTPIN (4700 3975) $PN 1
J 2
(4690 3985);
DISPLAY 0.680851 (4690 3985);
PAINT MONO (4690 3985);
FORCEPROP 0 LASTPIN (4700 4025) $PN 145
J 2
(4690 4035);
DISPLAY 0.680851 (4690 4035);
PAINT MONO (4690 4035);
FORCEPROP 0 LASTPIN (4700 4075) $PN 146
J 2
(4690 4085);
DISPLAY 0.680851 (4690 4085);
PAINT MONO (4690 4085);
FORCEPROP 0 LASTPIN (5900 925) $PN 6
J 0
(5910 935);
DISPLAY 0.680851 (5910 935);
PAINT MONO (5910 935);
FORCEPROP 0 LASTPIN (5900 975) $PN 8
J 0
(5910 985);
DISPLAY 0.680851 (5910 985);
PAINT MONO (5910 985);
FORCEPROP 0 LASTPIN (5900 1025) $PN 10
J 0
(5910 1035);
DISPLAY 0.680851 (5910 1035);
PAINT MONO (5910 1035);
FORCEPROP 0 LASTPIN (5900 1075) $PN 13
J 0
(5910 1085);
DISPLAY 0.680851 (5910 1085);
PAINT MONO (5910 1085);
FORCEPROP 0 LASTPIN (5900 1125) $PN 15
J 0
(5910 1135);
DISPLAY 0.680851 (5910 1135);
PAINT MONO (5910 1135);
FORCEPROP 0 LASTPIN (5900 1175) $PN 17
J 0
(5910 1185);
DISPLAY 0.680851 (5910 1185);
PAINT MONO (5910 1185);
FORCEPROP 0 LASTPIN (5900 1225) $PN 19
J 0
(5910 1235);
DISPLAY 0.680851 (5910 1235);
PAINT MONO (5910 1235);
FORCEPROP 0 LASTPIN (5900 1275) $PN 21
J 0
(5910 1285);
DISPLAY 0.680851 (5910 1285);
PAINT MONO (5910 1285);
FORCEPROP 0 LASTPIN (5900 1325) $PN 24
J 0
(5910 1335);
DISPLAY 0.680851 (5910 1335);
PAINT MONO (5910 1335);
FORCEPROP 0 LASTPIN (5900 1375) $PN 26
J 0
(5910 1385);
DISPLAY 0.680851 (5910 1385);
PAINT MONO (5910 1385);
FORCEPROP 0 LASTPIN (5900 1425) $PN 28
J 0
(5910 1435);
DISPLAY 0.680851 (5910 1435);
PAINT MONO (5910 1435);
FORCEPROP 0 LASTPIN (5900 1475) $PN 30
J 0
(5910 1485);
DISPLAY 0.680851 (5910 1485);
PAINT MONO (5910 1485);
FORCEPROP 0 LASTPIN (5900 1525) $PN 32
J 0
(5910 1535);
DISPLAY 0.680851 (5910 1535);
PAINT MONO (5910 1535);
FORCEPROP 0 LASTPIN (5900 1575) $PN 35
J 0
(5910 1585);
DISPLAY 0.680851 (5910 1585);
PAINT MONO (5910 1585);
FORCEPROP 0 LASTPIN (5900 1625) $PN 37
J 0
(5910 1635);
DISPLAY 0.680851 (5910 1635);
PAINT MONO (5910 1635);
FORCEPROP 0 LASTPIN (5900 1675) $PN 39
J 0
(5910 1685);
DISPLAY 0.680851 (5910 1685);
PAINT MONO (5910 1685);
FORCEPROP 0 LASTPIN (5900 1725) $PN 41
J 0
(5910 1735);
DISPLAY 0.680851 (5910 1735);
PAINT MONO (5910 1735);
FORCEPROP 0 LASTPIN (5900 1775) $PN 43
J 0
(5910 1785);
DISPLAY 0.680851 (5910 1785);
PAINT MONO (5910 1785);
FORCEPROP 0 LASTPIN (5900 1825) $PN 46
J 0
(5910 1835);
DISPLAY 0.680851 (5910 1835);
PAINT MONO (5910 1835);
FORCEPROP 0 LASTPIN (5900 1875) $PN 48
J 0
(5910 1885);
DISPLAY 0.680851 (5910 1885);
PAINT MONO (5910 1885);
FORCEPROP 0 LASTPIN (5900 1925) $PN 50
J 0
(5910 1935);
DISPLAY 0.680851 (5910 1935);
PAINT MONO (5910 1935);
FORCEPROP 0 LASTPIN (5900 1975) $PN 52
J 0
(5910 1985);
DISPLAY 0.680851 (5910 1985);
PAINT MONO (5910 1985);
FORCEPROP 0 LASTPIN (5900 2025) $PN 54
J 0
(5910 2035);
DISPLAY 0.680851 (5910 2035);
PAINT MONO (5910 2035);
FORCEPROP 0 LASTPIN (5900 2075) $PN 57
J 0
(5910 2085);
DISPLAY 0.680851 (5910 2085);
PAINT MONO (5910 2085);
FORCEPROP 0 LASTPIN (5900 2125) $PN 59
J 0
(5910 2135);
DISPLAY 0.680851 (5910 2135);
PAINT MONO (5910 2135);
FORCEPROP 0 LASTPIN (5900 2175) $PN 61
J 0
(5910 2185);
DISPLAY 0.680851 (5910 2185);
PAINT MONO (5910 2185);
FORCEPROP 0 LASTPIN (5900 2225) $PN 63
J 0
(5910 2235);
DISPLAY 0.680851 (5910 2235);
PAINT MONO (5910 2235);
FORCEPROP 0 LASTPIN (5900 2275) $PN 65
J 0
(5910 2285);
DISPLAY 0.680851 (5910 2285);
PAINT MONO (5910 2285);
FORCEPROP 0 LASTPIN (5900 2325) $PN 67
J 0
(5910 2335);
DISPLAY 0.680851 (5910 2335);
PAINT MONO (5910 2335);
FORCEPROP 0 LASTPIN (5900 2375) $PN 69
J 0
(5910 2385);
DISPLAY 0.680851 (5910 2385);
PAINT MONO (5910 2385);
FORCEPROP 0 LASTPIN (5900 2425) $PN 71
J 0
(5910 2435);
DISPLAY 0.680851 (5910 2435);
PAINT MONO (5910 2435);
FORCEPROP 0 LASTPIN (5900 2475) $PN 73
J 0
(5910 2485);
DISPLAY 0.680851 (5910 2485);
PAINT MONO (5910 2485);
FORCEPROP 0 LASTPIN (5900 2525) $PN 75
J 0
(5910 2535);
DISPLAY 0.680851 (5910 2535);
PAINT MONO (5910 2535);
FORCEPROP 0 LASTPIN (5900 2575) $PN 77
J 0
(5910 2585);
DISPLAY 0.680851 (5910 2585);
PAINT MONO (5910 2585);
FORCEPROP 0 LASTPIN (5900 2625) $PN 79
J 0
(5910 2635);
DISPLAY 0.680851 (5910 2635);
PAINT MONO (5910 2635);
FORCEPROP 0 LASTPIN (5900 2675) $PN 81
J 0
(5910 2685);
DISPLAY 0.680851 (5910 2685);
PAINT MONO (5910 2685);
FORCEPROP 0 LASTPIN (5900 2725) $PN 83
J 0
(5910 2735);
DISPLAY 0.680851 (5910 2735);
PAINT MONO (5910 2735);
FORCEPROP 0 LASTPIN (5900 2775) $PN 85
J 0
(5910 2785);
DISPLAY 0.680851 (5910 2785);
PAINT MONO (5910 2785);
FORCEPROP 0 LASTPIN (5900 2825) $PN 88
J 0
(5910 2835);
DISPLAY 0.680851 (5910 2835);
PAINT MONO (5910 2835);
FORCEPROP 0 LASTPIN (5900 2875) $PN 90
J 0
(5910 2885);
DISPLAY 0.680851 (5910 2885);
PAINT MONO (5910 2885);
FORCEPROP 0 LASTPIN (5900 2925) $PN 92
J 0
(5910 2935);
DISPLAY 0.680851 (5910 2935);
PAINT MONO (5910 2935);
FORCEPROP 0 LASTPIN (5900 2975) $PN 95
J 0
(5910 2985);
DISPLAY 0.680851 (5910 2985);
PAINT MONO (5910 2985);
FORCEPROP 0 LASTPIN (5900 3025) $PN 97
J 0
(5910 3035);
DISPLAY 0.680851 (5910 3035);
PAINT MONO (5910 3035);
FORCEPROP 0 LASTPIN (5900 3075) $PN 99
J 0
(5910 3085);
DISPLAY 0.680851 (5910 3085);
PAINT MONO (5910 3085);
FORCEPROP 0 LASTPIN (5900 3125) $PN 101
J 0
(5910 3135);
DISPLAY 0.680851 (5910 3135);
PAINT MONO (5910 3135);
FORCEPROP 0 LASTPIN (5900 3175) $PN 103
J 0
(5910 3185);
DISPLAY 0.680851 (5910 3185);
PAINT MONO (5910 3185);
FORCEPROP 0 LASTPIN (5900 3225) $PN 106
J 0
(5910 3235);
DISPLAY 0.680851 (5910 3235);
PAINT MONO (5910 3235);
FORCEPROP 0 LASTPIN (5900 3275) $PN 108
J 0
(5910 3285);
DISPLAY 0.680851 (5910 3285);
PAINT MONO (5910 3285);
FORCEPROP 0 LASTPIN (5900 3325) $PN 110
J 0
(5910 3335);
DISPLAY 0.680851 (5910 3335);
PAINT MONO (5910 3335);
FORCEPROP 0 LASTPIN (5900 3375) $PN 112
J 0
(5910 3385);
DISPLAY 0.680851 (5910 3385);
PAINT MONO (5910 3385);
FORCEPROP 0 LASTPIN (5900 3425) $PN 114
J 0
(5910 3435);
DISPLAY 0.680851 (5910 3435);
PAINT MONO (5910 3435);
FORCEPROP 0 LASTPIN (5900 3475) $PN 117
J 0
(5910 3485);
DISPLAY 0.680851 (5910 3485);
PAINT MONO (5910 3485);
FORCEPROP 0 LASTPIN (5900 3525) $PN 119
J 0
(5910 3535);
DISPLAY 0.680851 (5910 3535);
PAINT MONO (5910 3535);
FORCEPROP 0 LASTPIN (5900 3575) $PN 121
J 0
(5910 3585);
DISPLAY 0.680851 (5910 3585);
PAINT MONO (5910 3585);
FORCEPROP 0 LASTPIN (5900 3625) $PN 123
J 0
(5910 3635);
DISPLAY 0.680851 (5910 3635);
PAINT MONO (5910 3635);
FORCEPROP 0 LASTPIN (5900 3675) $PN 125
J 0
(5910 3685);
DISPLAY 0.680851 (5910 3685);
PAINT MONO (5910 3685);
FORCEPROP 0 LASTPIN (5900 3725) $PN 128
J 0
(5910 3735);
DISPLAY 0.680851 (5910 3735);
PAINT MONO (5910 3735);
FORCEPROP 0 LASTPIN (5900 3775) $PN 130
J 0
(5910 3785);
DISPLAY 0.680851 (5910 3785);
PAINT MONO (5910 3785);
FORCEPROP 0 LASTPIN (5900 3825) $PN 132
J 0
(5910 3835);
DISPLAY 0.680851 (5910 3835);
PAINT MONO (5910 3835);
FORCEPROP 0 LASTPIN (5900 3875) $PN 134
J 0
(5910 3885);
DISPLAY 0.680851 (5910 3885);
PAINT MONO (5910 3885);
FORCEPROP 0 LASTPIN (5900 3925) $PN 136
J 0
(5910 3935);
DISPLAY 0.680851 (5910 3935);
PAINT MONO (5910 3935);
FORCEPROP 0 LASTPIN (5900 3975) $PN 139
J 0
(5910 3985);
DISPLAY 0.680851 (5910 3985);
PAINT MONO (5910 3985);
FORCEPROP 0 LASTPIN (5900 4025) $PN 141
J 0
(5910 4035);
DISPLAY 0.680851 (5910 4035);
PAINT MONO (5910 4035);
FORCEPROP 0 LASTPIN (5900 4075) $PN 143
J 0
(5910 4085);
DISPLAY 0.680851 (5910 4085);
PAINT MONO (5910 4085);
FORCEPROP 0 LASTPIN (4700 825) $PN 151
J 2
(4690 835);
DISPLAY 0.680851 (4690 835);
PAINT MONO (4690 835);
FORCEPROP 0 LASTPIN (4700 875) $PN 153
J 2
(4690 885);
DISPLAY 0.680851 (4690 885);
PAINT MONO (4690 885);
FORCEPROP 0 LASTPIN (4700 925) $PN 155
J 2
(4690 935);
DISPLAY 0.680851 (4690 935);
PAINT MONO (4690 935);
FORCEPROP 0 LASTPIN (4700 975) $PN 158
J 2
(4690 985);
DISPLAY 0.680851 (4690 985);
PAINT MONO (4690 985);
FORCEPROP 0 LASTPIN (4700 1025) $PN 160
J 2
(4690 1035);
DISPLAY 0.680851 (4690 1035);
PAINT MONO (4690 1035);
FORCEPROP 0 LASTPIN (4700 1075) $PN 162
J 2
(4690 1085);
DISPLAY 0.680851 (4690 1085);
PAINT MONO (4690 1085);
FORCEPROP 0 LASTPIN (4700 1125) $PN 164
J 2
(4690 1135);
DISPLAY 0.680851 (4690 1135);
PAINT MONO (4690 1135);
FORCEPROP 0 LASTPIN (4700 1175) $PN 166
J 2
(4690 1185);
DISPLAY 0.680851 (4690 1185);
PAINT MONO (4690 1185);
FORCEPROP 0 LASTPIN (4700 1225) $PN 169
J 2
(4690 1235);
DISPLAY 0.680851 (4690 1235);
PAINT MONO (4690 1235);
FORCEPROP 0 LASTPIN (4700 1275) $PN 171
J 2
(4690 1285);
DISPLAY 0.680851 (4690 1285);
PAINT MONO (4690 1285);
FORCEPROP 0 LASTPIN (4700 1325) $PN 173
J 2
(4690 1335);
DISPLAY 0.680851 (4690 1335);
PAINT MONO (4690 1335);
FORCEPROP 0 LASTPIN (4700 1375) $PN 175
J 2
(4690 1385);
DISPLAY 0.680851 (4690 1385);
PAINT MONO (4690 1385);
FORCEPROP 0 LASTPIN (4700 1425) $PN 177
J 2
(4690 1435);
DISPLAY 0.680851 (4690 1435);
PAINT MONO (4690 1435);
FORCEPROP 0 LASTPIN (4700 1475) $PN 180
J 2
(4690 1485);
DISPLAY 0.680851 (4690 1485);
PAINT MONO (4690 1485);
FORCEPROP 0 LASTPIN (4700 1525) $PN 182
J 2
(4690 1535);
DISPLAY 0.680851 (4690 1535);
PAINT MONO (4690 1535);
FORCEPROP 0 LASTPIN (4700 1575) $PN 184
J 2
(4690 1585);
DISPLAY 0.680851 (4690 1585);
PAINT MONO (4690 1585);
FORCEPROP 0 LASTPIN (4700 1625) $PN 186
J 2
(4690 1635);
DISPLAY 0.680851 (4690 1635);
PAINT MONO (4690 1635);
FORCEPROP 0 LASTPIN (4700 1675) $PN 188
J 2
(4690 1685);
DISPLAY 0.680851 (4690 1685);
PAINT MONO (4690 1685);
FORCEPROP 0 LASTPIN (4700 1725) $PN 191
J 2
(4690 1735);
DISPLAY 0.680851 (4690 1735);
PAINT MONO (4690 1735);
FORCEPROP 0 LASTPIN (4700 1775) $PN 193
J 2
(4690 1785);
DISPLAY 0.680851 (4690 1785);
PAINT MONO (4690 1785);
FORCEPROP 0 LASTPIN (4700 1825) $PN 195
J 2
(4690 1835);
DISPLAY 0.680851 (4690 1835);
PAINT MONO (4690 1835);
FORCEPROP 0 LASTPIN (4700 1875) $PN 197
J 2
(4690 1885);
DISPLAY 0.680851 (4690 1885);
PAINT MONO (4690 1885);
FORCEPROP 0 LASTPIN (4700 1925) $PN 199
J 2
(4690 1935);
DISPLAY 0.680851 (4690 1935);
PAINT MONO (4690 1935);
FORCEPROP 0 LASTPIN (4700 1975) $PN 202
J 2
(4690 1985);
DISPLAY 0.680851 (4690 1985);
PAINT MONO (4690 1985);
FORCEPROP 0 LASTPIN (4700 2025) $PN 204
J 2
(4690 2035);
DISPLAY 0.680851 (4690 2035);
PAINT MONO (4690 2035);
FORCEPROP 0 LASTPIN (4700 2075) $PN 206
J 2
(4690 2085);
DISPLAY 0.680851 (4690 2085);
PAINT MONO (4690 2085);
FORCEPROP 0 LASTPIN (4700 2125) $PN 208
J 2
(4690 2135);
DISPLAY 0.680851 (4690 2135);
PAINT MONO (4690 2135);
FORCEPROP 0 LASTPIN (4700 2175) $PN 210
J 2
(4690 2185);
DISPLAY 0.680851 (4690 2185);
PAINT MONO (4690 2185);
FORCEPROP 0 LASTPIN (4700 2225) $PN 212
J 2
(4690 2235);
DISPLAY 0.680851 (4690 2235);
PAINT MONO (4690 2235);
FORCEPROP 0 LASTPIN (4700 2275) $PN 214
J 2
(4690 2285);
DISPLAY 0.680851 (4690 2285);
PAINT MONO (4690 2285);
FORCEPROP 0 LASTPIN (4700 2325) $PN 216
J 2
(4690 2335);
DISPLAY 0.680851 (4690 2335);
PAINT MONO (4690 2335);
FORCEPROP 0 LASTPIN (4700 2375) $PN 219
J 2
(4690 2385);
DISPLAY 0.680851 (4690 2385);
PAINT MONO (4690 2385);
FORCEPROP 0 LASTPIN (4700 2425) $PN 222
J 2
(4690 2435);
DISPLAY 0.680851 (4690 2435);
PAINT MONO (4690 2435);
FORCEPROP 0 LASTPIN (4700 2475) $PN 224
J 2
(4690 2485);
DISPLAY 0.680851 (4690 2485);
PAINT MONO (4690 2485);
FORCEPROP 0 LASTPIN (4700 2525) $PN 226
J 2
(4690 2535);
DISPLAY 0.680851 (4690 2535);
PAINT MONO (4690 2535);
FORCEPROP 0 LASTPIN (4700 2575) $PN 228
J 2
(4690 2585);
DISPLAY 0.680851 (4690 2585);
PAINT MONO (4690 2585);
FORCEPROP 0 LASTPIN (4700 2625) $PN 230
J 2
(4690 2635);
DISPLAY 0.680851 (4690 2635);
PAINT MONO (4690 2635);
FORCEPROP 0 LASTPIN (4700 2675) $PN 233
J 2
(4690 2685);
DISPLAY 0.680851 (4690 2685);
PAINT MONO (4690 2685);
FORCEPROP 0 LASTPIN (4700 2725) $PN 235
J 2
(4690 2735);
DISPLAY 0.680851 (4690 2735);
PAINT MONO (4690 2735);
FORCEPROP 0 LASTPIN (4700 2775) $PN 237
J 2
(4690 2785);
DISPLAY 0.680851 (4690 2785);
PAINT MONO (4690 2785);
FORCEPROP 0 LASTPIN (4700 2825) $PN 240
J 2
(4690 2835);
DISPLAY 0.680851 (4690 2835);
PAINT MONO (4690 2835);
FORCEPROP 0 LASTPIN (4700 2875) $PN 242
J 2
(4690 2885);
DISPLAY 0.680851 (4690 2885);
PAINT MONO (4690 2885);
FORCEPROP 0 LASTPIN (4700 2925) $PN 244
J 2
(4690 2935);
DISPLAY 0.680851 (4690 2935);
PAINT MONO (4690 2935);
FORCEPROP 0 LASTPIN (4700 2975) $PN 246
J 2
(4690 2985);
DISPLAY 0.680851 (4690 2985);
PAINT MONO (4690 2985);
FORCEPROP 0 LASTPIN (4700 3025) $PN 248
J 2
(4690 3035);
DISPLAY 0.680851 (4690 3035);
PAINT MONO (4690 3035);
FORCEPROP 0 LASTPIN (4700 3075) $PN 251
J 2
(4690 3085);
DISPLAY 0.680851 (4690 3085);
PAINT MONO (4690 3085);
FORCEPROP 0 LASTPIN (4700 3125) $PN 253
J 2
(4690 3135);
DISPLAY 0.680851 (4690 3135);
PAINT MONO (4690 3135);
FORCEPROP 0 LASTPIN (4700 3175) $PN 255
J 2
(4690 3185);
DISPLAY 0.680851 (4690 3185);
PAINT MONO (4690 3185);
FORCEPROP 0 LASTPIN (4700 3225) $PN 257
J 2
(4690 3235);
DISPLAY 0.680851 (4690 3235);
PAINT MONO (4690 3235);
FORCEPROP 0 LASTPIN (4700 3275) $PN 259
J 2
(4690 3285);
DISPLAY 0.680851 (4690 3285);
PAINT MONO (4690 3285);
FORCEPROP 0 LASTPIN (4700 3325) $PN 262
J 2
(4690 3335);
DISPLAY 0.680851 (4690 3335);
PAINT MONO (4690 3335);
FORCEPROP 0 LASTPIN (4700 3375) $PN 264
J 2
(4690 3385);
DISPLAY 0.680851 (4690 3385);
PAINT MONO (4690 3385);
FORCEPROP 0 LASTPIN (4700 3425) $PN 266
J 2
(4690 3435);
DISPLAY 0.680851 (4690 3435);
PAINT MONO (4690 3435);
FORCEPROP 0 LASTPIN (4700 3475) $PN 268
J 2
(4690 3485);
DISPLAY 0.680851 (4690 3485);
PAINT MONO (4690 3485);
FORCEPROP 0 LASTPIN (4700 3525) $PN 270
J 2
(4690 3535);
DISPLAY 0.680851 (4690 3535);
PAINT MONO (4690 3535);
FORCEPROP 0 LASTPIN (4700 3575) $PN 273
J 2
(4690 3585);
DISPLAY 0.680851 (4690 3585);
PAINT MONO (4690 3585);
FORCEPROP 0 LASTPIN (4700 3625) $PN 275
J 2
(4690 3635);
DISPLAY 0.680851 (4690 3635);
PAINT MONO (4690 3635);
FORCEPROP 0 LASTPIN (4700 3675) $PN 277
J 2
(4690 3685);
DISPLAY 0.680851 (4690 3685);
PAINT MONO (4690 3685);
FORCEPROP 0 LASTPIN (4700 3725) $PN 279
J 2
(4690 3735);
DISPLAY 0.680851 (4690 3735);
PAINT MONO (4690 3735);
FORCEPROP 0 LASTPIN (4700 3775) $PN 281
J 2
(4690 3785);
DISPLAY 0.680851 (4690 3785);
PAINT MONO (4690 3785);
FORCEPROP 0 LASTPIN (4700 3825) $PN 284
J 2
(4690 3835);
DISPLAY 0.680851 (4690 3835);
PAINT MONO (4690 3835);
FORCEPROP 0 LASTPIN (4700 3875) $PN 286
J 2
(4690 3885);
DISPLAY 0.680851 (4690 3885);
PAINT MONO (4690 3885);
FORCEPROP 0 LASTPIN (4700 3925) $PN 288
J 2
(4690 3935);
DISPLAY 0.680851 (4690 3935);
PAINT MONO (4690 3935);
FORCEPROP 1 LAST NEEDS_NO_SIZE TRUE
J 0
(5300 2450);
DISPLAY 0.723404 (5300 2450);
PAINT GREEN (5300 2450);
DISPLAY INVISIBLE (5300 2450);
FORCEPROP 1 LAST CDS_LMAN_SYM_OUTLINE -450,1775,450,-1775
J 0
(5300 2450);
DISPLAY 0.468085 (5300 2450);
PAINT GREEN (5300 2450);
DISPLAY INVISIBLE (5300 2450);
FORCEPROP 2 LAST CDS_LIB pure_quanta
J 0
(5300 2450);
DISPLAY INVISIBLE (5300 2450);
FORCEPROP 2 LAST CDS_LOCATION J17
J 0
(4850 4575);
DISPLAY 1.021277 (4850 4575);
DISPLAY INVISIBLE (4850 4575);
FORCEPROP 0 LAST $SEC 3
J 0
(4850 4575);
DISPLAY 0.680851 (4850 4575);
PAINT MONO (4850 4575);
DISPLAY INVISIBLE (4850 4575);
FORCEPROP 2 LAST CDS_SEC 3
J 0
(4850 4575);
DISPLAY 1.021277 (4850 4575);
DISPLAY INVISIBLE (4850 4575);
FORCEPROP 1 LAST PATH I147
J 0
(5300 2450);
DISPLAY 0.723404 (5300 2450);
PAINT GREEN (5300 2450);
DISPLAY INVISIBLE (5300 2450);
FORCEADD TAP..1
(2950 2075);
FORCEPROP 3 LASTPIN (2900 2075) SIG_NAME M_A_CPU1_SB_DQS_DN<0>
J 0
(2910 2085);
DISPLAY 0.659574 (2910 2085);
PAINT MONO (2910 2085);
DISPLAY INVISIBLE (2910 2085);
FORCEPROP 1 LASTPIN (2900 2075) BN 0
J 0
(2888 2083);
DISPLAY 0.680851 (2888 2083);
PAINT GREEN (2888 2083);
FORCEPROP 2 LAST CDS_LIB standard
J 0
(2950 2075);
PAINT MONO (2950 2075);
DISPLAY INVISIBLE (2950 2075);
FORCEPROP 1 LAST BODY_TYPE PLUMBING
J 0
(2950 2125);
DISPLAY 0.872340 (2950 2125);
PAINT GREEN (2950 2125);
DISPLAY INVISIBLE (2950 2125);
FORCEPROP 1 LAST HDL_TAP TRUE
J 0
(3275 1950);
DISPLAY 0.872340 (3275 1950);
DISPLAY INVISIBLE (3275 1950);
FORCEPROP 1 LAST PATH I148
J 0
(2948 2075);
DISPLAY 0.872340 (2948 2075);
PAINT GREEN (2948 2075);
DISPLAY INVISIBLE (2948 2075);
FORCEADD TAP..1
(2950 2175);
FORCEPROP 3 LASTPIN (2900 2175) SIG_NAME M_A_CPU1_SB_DQS_DN<1>
J 0
(2910 2185);
DISPLAY 0.659574 (2910 2185);
PAINT MONO (2910 2185);
DISPLAY INVISIBLE (2910 2185);
FORCEPROP 1 LASTPIN (2900 2175) BN 1
J 0
(2888 2183);
DISPLAY 0.680851 (2888 2183);
PAINT GREEN (2888 2183);
FORCEPROP 2 LAST CDS_LIB standard
J 0
(2950 2175);
DISPLAY INVISIBLE (2950 2175);
FORCEPROP 1 LAST BODY_TYPE PLUMBING
J 0
(2950 2225);
DISPLAY 0.872340 (2950 2225);
PAINT GREEN (2950 2225);
DISPLAY INVISIBLE (2950 2225);
FORCEPROP 1 LAST HDL_TAP TRUE
J 0
(3275 2050);
DISPLAY 0.872340 (3275 2050);
DISPLAY INVISIBLE (3275 2050);
FORCEPROP 1 LAST PATH I149
J 0
(2948 2175);
DISPLAY 0.872340 (2948 2175);
PAINT GREEN (2948 2175);
DISPLAY INVISIBLE (2948 2175);
FORCEADD OFFPAGE..3
R 2
(-2550 2700);
FORCEPROP 2 LAST $XR1 99 
J 0
(-2889 2700);
DISPLAY 0.638298 (-2889 2700);
PAINT MONO (-2889 2700);
FORCEPROP 2 LAST $XR0 51 
J 0
(-2799 2700);
DISPLAY 0.638298 (-2799 2700);
PAINT MONO (-2799 2700);
FORCEPROP 2 LAST CDS_LIB standard
J 0
(-2550 2700);
PAINT MONO (-2550 2700);
DISPLAY INVISIBLE (-2550 2700);
FORCEPROP 1 LAST OFFPAGE TRUE
J 2
(-2875 2575);
DISPLAY 0.872340 (-2875 2575);
DISPLAY INVISIBLE (-2875 2575);
FORCEPROP 1 LAST COMMENT_BODY TRUE
J 2
(-2500 2600);
DISPLAY 0.872340 (-2500 2600);
PAINT GREEN (-2500 2600);
DISPLAY INVISIBLE (-2500 2600);
FORCEPROP 2 LAST PATH I15
J 0
(-2500 2775);
DISPLAY 1.021277 (-2500 2775);
DISPLAY INVISIBLE (-2500 2775);
FORCEADD TAP..1
(2950 2275);
FORCEPROP 3 LASTPIN (2900 2275) SIG_NAME M_A_CPU1_SB_DQS_DN<2>
J 0
(2910 2285);
DISPLAY 0.659574 (2910 2285);
PAINT MONO (2910 2285);
DISPLAY INVISIBLE (2910 2285);
FORCEPROP 1 LASTPIN (2900 2275) BN 2
J 0
(2888 2283);
DISPLAY 0.680851 (2888 2283);
PAINT GREEN (2888 2283);
FORCEPROP 2 LAST CDS_LIB standard
J 0
(2950 2275);
DISPLAY INVISIBLE (2950 2275);
FORCEPROP 1 LAST BODY_TYPE PLUMBING
J 0
(2950 2325);
DISPLAY 0.872340 (2950 2325);
PAINT GREEN (2950 2325);
DISPLAY INVISIBLE (2950 2325);
FORCEPROP 1 LAST HDL_TAP TRUE
J 0
(3275 2150);
DISPLAY 0.872340 (3275 2150);
DISPLAY INVISIBLE (3275 2150);
FORCEPROP 1 LAST PATH I150
J 0
(2948 2275);
DISPLAY 0.872340 (2948 2275);
PAINT GREEN (2948 2275);
DISPLAY INVISIBLE (2948 2275);
FORCEADD TAP..1
(2950 2375);
FORCEPROP 3 LASTPIN (2900 2375) SIG_NAME M_A_CPU1_SB_DQS_DN<3>
J 0
(2910 2385);
DISPLAY 0.659574 (2910 2385);
PAINT MONO (2910 2385);
DISPLAY INVISIBLE (2910 2385);
FORCEPROP 1 LASTPIN (2900 2375) BN 3
J 0
(2888 2383);
DISPLAY 0.680851 (2888 2383);
PAINT GREEN (2888 2383);
FORCEPROP 2 LAST CDS_LIB standard
J 0
(2950 2375);
PAINT MONO (2950 2375);
DISPLAY INVISIBLE (2950 2375);
FORCEPROP 1 LAST BODY_TYPE PLUMBING
J 0
(2950 2425);
DISPLAY 0.872340 (2950 2425);
PAINT GREEN (2950 2425);
DISPLAY INVISIBLE (2950 2425);
FORCEPROP 1 LAST HDL_TAP TRUE
J 0
(3275 2250);
DISPLAY 0.872340 (3275 2250);
DISPLAY INVISIBLE (3275 2250);
FORCEPROP 1 LAST PATH I151
J 0
(2948 2375);
DISPLAY 0.872340 (2948 2375);
PAINT GREEN (2948 2375);
DISPLAY INVISIBLE (2948 2375);
FORCEADD TAP..1
(2950 2575);
FORCEPROP 3 LASTPIN (2900 2575) SIG_NAME M_A_CPU1_SB_DQS_DN<5>
J 0
(2910 2585);
DISPLAY 0.659574 (2910 2585);
PAINT MONO (2910 2585);
DISPLAY INVISIBLE (2910 2585);
FORCEPROP 1 LASTPIN (2900 2575) BN 5
J 0
(2888 2583);
DISPLAY 0.680851 (2888 2583);
PAINT GREEN (2888 2583);
FORCEPROP 2 LAST CDS_LIB standard
J 0
(2950 2575);
DISPLAY INVISIBLE (2950 2575);
FORCEPROP 1 LAST BODY_TYPE PLUMBING
J 0
(2950 2625);
DISPLAY 0.872340 (2950 2625);
PAINT GREEN (2950 2625);
DISPLAY INVISIBLE (2950 2625);
FORCEPROP 1 LAST HDL_TAP TRUE
J 0
(3275 2450);
DISPLAY 0.872340 (3275 2450);
DISPLAY INVISIBLE (3275 2450);
FORCEPROP 1 LAST PATH I152
J 0
(2948 2575);
DISPLAY 0.872340 (2948 2575);
PAINT GREEN (2948 2575);
DISPLAY INVISIBLE (2948 2575);
FORCEADD TAP..1
(2950 2475);
FORCEPROP 3 LASTPIN (2900 2475) SIG_NAME M_A_CPU1_SB_DQS_DN<4>
J 0
(2910 2485);
DISPLAY 0.659574 (2910 2485);
PAINT MONO (2910 2485);
DISPLAY INVISIBLE (2910 2485);
FORCEPROP 1 LASTPIN (2900 2475) BN 4
J 0
(2888 2483);
DISPLAY 0.680851 (2888 2483);
PAINT GREEN (2888 2483);
FORCEPROP 2 LAST CDS_LIB standard
J 0
(2950 2475);
PAINT MONO (2950 2475);
DISPLAY INVISIBLE (2950 2475);
FORCEPROP 1 LAST BODY_TYPE PLUMBING
J 0
(2950 2525);
DISPLAY 0.872340 (2950 2525);
PAINT GREEN (2950 2525);
DISPLAY INVISIBLE (2950 2525);
FORCEPROP 1 LAST HDL_TAP TRUE
J 0
(3275 2350);
DISPLAY 0.872340 (3275 2350);
DISPLAY INVISIBLE (3275 2350);
FORCEPROP 1 LAST PATH I153
J 0
(2948 2475);
DISPLAY 0.872340 (2948 2475);
PAINT GREEN (2948 2475);
DISPLAY INVISIBLE (2948 2475);
FORCEADD TAP..1
(2950 2675);
FORCEPROP 3 LASTPIN (2900 2675) SIG_NAME M_A_CPU1_SB_DQS_DN<6>
J 0
(2910 2685);
DISPLAY 0.659574 (2910 2685);
PAINT MONO (2910 2685);
DISPLAY INVISIBLE (2910 2685);
FORCEPROP 1 LASTPIN (2900 2675) BN 6
J 0
(2888 2683);
DISPLAY 0.680851 (2888 2683);
PAINT GREEN (2888 2683);
FORCEPROP 2 LAST CDS_LIB standard
J 0
(2950 2675);
DISPLAY INVISIBLE (2950 2675);
FORCEPROP 1 LAST BODY_TYPE PLUMBING
J 0
(2950 2725);
DISPLAY 0.872340 (2950 2725);
PAINT GREEN (2950 2725);
DISPLAY INVISIBLE (2950 2725);
FORCEPROP 1 LAST HDL_TAP TRUE
J 0
(3275 2550);
DISPLAY 0.872340 (3275 2550);
DISPLAY INVISIBLE (3275 2550);
FORCEPROP 1 LAST PATH I154
J 0
(2948 2675);
DISPLAY 0.872340 (2948 2675);
PAINT GREEN (2948 2675);
DISPLAY INVISIBLE (2948 2675);
FORCEADD TAP..1
(2950 2775);
FORCEPROP 3 LASTPIN (2900 2775) SIG_NAME M_A_CPU1_SB_DQS_DN<7>
J 0
(2910 2785);
DISPLAY 0.659574 (2910 2785);
PAINT MONO (2910 2785);
DISPLAY INVISIBLE (2910 2785);
FORCEPROP 1 LASTPIN (2900 2775) BN 7
J 0
(2888 2783);
DISPLAY 0.680851 (2888 2783);
PAINT GREEN (2888 2783);
FORCEPROP 2 LAST CDS_LIB standard
J 0
(2950 2775);
DISPLAY INVISIBLE (2950 2775);
FORCEPROP 1 LAST BODY_TYPE PLUMBING
J 0
(2950 2825);
DISPLAY 0.872340 (2950 2825);
PAINT GREEN (2950 2825);
DISPLAY INVISIBLE (2950 2825);
FORCEPROP 1 LAST HDL_TAP TRUE
J 0
(3275 2650);
DISPLAY 0.872340 (3275 2650);
DISPLAY INVISIBLE (3275 2650);
FORCEPROP 1 LAST PATH I155
J 0
(2948 2775);
DISPLAY 0.872340 (2948 2775);
PAINT GREEN (2948 2775);
DISPLAY INVISIBLE (2948 2775);
FORCEADD TAP..1
(2950 2875);
FORCEPROP 3 LASTPIN (2900 2875) SIG_NAME M_A_CPU1_SB_DQS_DN<8>
J 0
(2910 2885);
DISPLAY 0.659574 (2910 2885);
PAINT MONO (2910 2885);
DISPLAY INVISIBLE (2910 2885);
FORCEPROP 1 LASTPIN (2900 2875) BN 8
J 0
(2888 2883);
DISPLAY 0.680851 (2888 2883);
PAINT GREEN (2888 2883);
FORCEPROP 2 LAST CDS_LIB standard
J 0
(2950 2875);
DISPLAY INVISIBLE (2950 2875);
FORCEPROP 1 LAST BODY_TYPE PLUMBING
J 0
(2950 2925);
DISPLAY 0.872340 (2950 2925);
PAINT GREEN (2950 2925);
DISPLAY INVISIBLE (2950 2925);
FORCEPROP 1 LAST HDL_TAP TRUE
J 0
(3275 2750);
DISPLAY 0.872340 (3275 2750);
DISPLAY INVISIBLE (3275 2750);
FORCEPROP 1 LAST PATH I156
J 0
(2948 2875);
DISPLAY 0.872340 (2948 2875);
PAINT GREEN (2948 2875);
DISPLAY INVISIBLE (2948 2875);
FORCEADD TAP..1
(2950 2975);
FORCEPROP 3 LASTPIN (2900 2975) SIG_NAME M_A_CPU1_SB_DQS_DN<9>
J 0
(2910 2985);
DISPLAY 0.659574 (2910 2985);
PAINT MONO (2910 2985);
DISPLAY INVISIBLE (2910 2985);
FORCEPROP 1 LASTPIN (2900 2975) BN 9
J 0
(2888 2983);
DISPLAY 0.680851 (2888 2983);
PAINT GREEN (2888 2983);
FORCEPROP 2 LAST CDS_LIB standard
J 0
(2950 2975);
DISPLAY INVISIBLE (2950 2975);
FORCEPROP 1 LAST BODY_TYPE PLUMBING
J 0
(2950 3025);
DISPLAY 0.872340 (2950 3025);
PAINT GREEN (2950 3025);
DISPLAY INVISIBLE (2950 3025);
FORCEPROP 1 LAST HDL_TAP TRUE
J 0
(3275 2850);
DISPLAY 0.872340 (3275 2850);
DISPLAY INVISIBLE (3275 2850);
FORCEPROP 1 LAST PATH I157
J 0
(2948 2975);
DISPLAY 0.872340 (2948 2975);
PAINT GREEN (2948 2975);
DISPLAY INVISIBLE (2948 2975);
FORCEADD TAP..1
(2950 3225);
FORCEPROP 3 LASTPIN (2900 3225) SIG_NAME M_A_CPU1_SA_DQS_DN<1>
J 0
(2910 3235);
DISPLAY 0.659574 (2910 3235);
PAINT MONO (2910 3235);
DISPLAY INVISIBLE (2910 3235);
FORCEPROP 1 LASTPIN (2900 3225) BN 1
J 0
(2888 3233);
DISPLAY 0.680851 (2888 3233);
PAINT GREEN (2888 3233);
FORCEPROP 2 LAST CDS_LIB standard
J 0
(2950 3225);
DISPLAY INVISIBLE (2950 3225);
FORCEPROP 1 LAST BODY_TYPE PLUMBING
J 0
(2950 3275);
DISPLAY 0.872340 (2950 3275);
PAINT GREEN (2950 3275);
DISPLAY INVISIBLE (2950 3275);
FORCEPROP 1 LAST HDL_TAP TRUE
J 0
(3275 3100);
DISPLAY 0.872340 (3275 3100);
DISPLAY INVISIBLE (3275 3100);
FORCEPROP 1 LAST PATH I158
J 0
(2948 3225);
DISPLAY 0.872340 (2948 3225);
PAINT GREEN (2948 3225);
DISPLAY INVISIBLE (2948 3225);
FORCEADD TAP..1
(2950 3125);
FORCEPROP 3 LASTPIN (2900 3125) SIG_NAME M_A_CPU1_SA_DQS_DN<0>
J 0
(2910 3135);
DISPLAY 0.659574 (2910 3135);
PAINT MONO (2910 3135);
DISPLAY INVISIBLE (2910 3135);
FORCEPROP 1 LASTPIN (2900 3125) BN 0
J 0
(2888 3133);
DISPLAY 0.680851 (2888 3133);
PAINT GREEN (2888 3133);
FORCEPROP 2 LAST CDS_LIB standard
J 0
(2950 3125);
PAINT MONO (2950 3125);
DISPLAY INVISIBLE (2950 3125);
FORCEPROP 1 LAST BODY_TYPE PLUMBING
J 0
(2950 3175);
DISPLAY 0.872340 (2950 3175);
PAINT GREEN (2950 3175);
DISPLAY INVISIBLE (2950 3175);
FORCEPROP 1 LAST HDL_TAP TRUE
J 0
(3275 3000);
DISPLAY 0.872340 (3275 3000);
DISPLAY INVISIBLE (3275 3000);
FORCEPROP 1 LAST PATH I159
J 0
(2948 3125);
DISPLAY 0.872340 (2948 3125);
PAINT GREEN (2948 3125);
DISPLAY INVISIBLE (2948 3125);
FORCEADD OFFPAGE..1
(-2550 2775);
FORCEPROP 2 LAST $XR0 51 
J 0
(-2771 2775);
DISPLAY 0.638298 (-2771 2775);
PAINT MONO (-2771 2775);
FORCEPROP 2 LAST CDS_LIB standard
J 0
(-2550 2775);
PAINT MONO (-2550 2775);
DISPLAY INVISIBLE (-2550 2775);
FORCEPROP 1 LAST OFFPAGE TRUE
J 0
(-2225 2650);
DISPLAY 0.872340 (-2225 2650);
DISPLAY INVISIBLE (-2225 2650);
FORCEPROP 1 LAST COMMENT_BODY TRUE
J 0
(-2425 2675);
DISPLAY 0.872340 (-2425 2675);
PAINT GREEN (-2425 2675);
DISPLAY INVISIBLE (-2425 2675);
FORCEPROP 2 LAST PATH I16
J 0
(-2500 2850);
DISPLAY 1.021277 (-2500 2850);
DISPLAY INVISIBLE (-2500 2850);
FORCEADD TAP..1
(2950 3325);
FORCEPROP 3 LASTPIN (2900 3325) SIG_NAME M_A_CPU1_SA_DQS_DN<2>
J 0
(2910 3335);
DISPLAY 0.659574 (2910 3335);
PAINT MONO (2910 3335);
DISPLAY INVISIBLE (2910 3335);
FORCEPROP 1 LASTPIN (2900 3325) BN 2
J 0
(2888 3333);
DISPLAY 0.680851 (2888 3333);
PAINT GREEN (2888 3333);
FORCEPROP 2 LAST CDS_LIB standard
J 0
(2950 3325);
DISPLAY INVISIBLE (2950 3325);
FORCEPROP 1 LAST BODY_TYPE PLUMBING
J 0
(2950 3375);
DISPLAY 0.872340 (2950 3375);
PAINT GREEN (2950 3375);
DISPLAY INVISIBLE (2950 3375);
FORCEPROP 1 LAST HDL_TAP TRUE
J 0
(3275 3200);
DISPLAY 0.872340 (3275 3200);
DISPLAY INVISIBLE (3275 3200);
FORCEPROP 1 LAST PATH I160
J 0
(2948 3325);
DISPLAY 0.872340 (2948 3325);
PAINT GREEN (2948 3325);
DISPLAY INVISIBLE (2948 3325);
FORCEADD TAP..1
(2950 3425);
FORCEPROP 3 LASTPIN (2900 3425) SIG_NAME M_A_CPU1_SA_DQS_DN<3>
J 0
(2910 3435);
DISPLAY 0.659574 (2910 3435);
PAINT MONO (2910 3435);
DISPLAY INVISIBLE (2910 3435);
FORCEPROP 1 LASTPIN (2900 3425) BN 3
J 0
(2888 3433);
DISPLAY 0.680851 (2888 3433);
PAINT GREEN (2888 3433);
FORCEPROP 2 LAST CDS_LIB standard
J 0
(2950 3425);
PAINT MONO (2950 3425);
DISPLAY INVISIBLE (2950 3425);
FORCEPROP 1 LAST BODY_TYPE PLUMBING
J 0
(2950 3475);
DISPLAY 0.872340 (2950 3475);
PAINT GREEN (2950 3475);
DISPLAY INVISIBLE (2950 3475);
FORCEPROP 1 LAST HDL_TAP TRUE
J 0
(3275 3300);
DISPLAY 0.872340 (3275 3300);
DISPLAY INVISIBLE (3275 3300);
FORCEPROP 1 LAST PATH I161
J 0
(2948 3425);
DISPLAY 0.872340 (2948 3425);
PAINT GREEN (2948 3425);
DISPLAY INVISIBLE (2948 3425);
FORCEADD TAP..1
(2950 3525);
FORCEPROP 3 LASTPIN (2900 3525) SIG_NAME M_A_CPU1_SA_DQS_DN<4>
J 0
(2910 3535);
DISPLAY 0.659574 (2910 3535);
PAINT MONO (2910 3535);
DISPLAY INVISIBLE (2910 3535);
FORCEPROP 1 LASTPIN (2900 3525) BN 4
J 0
(2888 3533);
DISPLAY 0.680851 (2888 3533);
PAINT GREEN (2888 3533);
FORCEPROP 2 LAST CDS_LIB standard
J 0
(2950 3525);
PAINT MONO (2950 3525);
DISPLAY INVISIBLE (2950 3525);
FORCEPROP 1 LAST BODY_TYPE PLUMBING
J 0
(2950 3575);
DISPLAY 0.872340 (2950 3575);
PAINT GREEN (2950 3575);
DISPLAY INVISIBLE (2950 3575);
FORCEPROP 1 LAST HDL_TAP TRUE
J 0
(3275 3400);
DISPLAY 0.872340 (3275 3400);
DISPLAY INVISIBLE (3275 3400);
FORCEPROP 1 LAST PATH I162
J 0
(2948 3525);
DISPLAY 0.872340 (2948 3525);
PAINT GREEN (2948 3525);
DISPLAY INVISIBLE (2948 3525);
FORCEADD TAP..1
(2950 3725);
FORCEPROP 3 LASTPIN (2900 3725) SIG_NAME M_A_CPU1_SA_DQS_DN<6>
J 0
(2910 3735);
DISPLAY 0.659574 (2910 3735);
PAINT MONO (2910 3735);
DISPLAY INVISIBLE (2910 3735);
FORCEPROP 1 LASTPIN (2900 3725) BN 6
J 0
(2888 3733);
DISPLAY 0.680851 (2888 3733);
PAINT GREEN (2888 3733);
FORCEPROP 2 LAST CDS_LIB standard
J 0
(2950 3725);
DISPLAY INVISIBLE (2950 3725);
FORCEPROP 1 LAST BODY_TYPE PLUMBING
J 0
(2950 3775);
DISPLAY 0.872340 (2950 3775);
PAINT GREEN (2950 3775);
DISPLAY INVISIBLE (2950 3775);
FORCEPROP 1 LAST HDL_TAP TRUE
J 0
(3275 3600);
DISPLAY 0.872340 (3275 3600);
DISPLAY INVISIBLE (3275 3600);
FORCEPROP 1 LAST PATH I163
J 0
(2948 3725);
DISPLAY 0.872340 (2948 3725);
PAINT GREEN (2948 3725);
DISPLAY INVISIBLE (2948 3725);
FORCEADD TAP..1
(2950 3625);
FORCEPROP 3 LASTPIN (2900 3625) SIG_NAME M_A_CPU1_SA_DQS_DN<5>
J 0
(2910 3635);
DISPLAY 0.659574 (2910 3635);
PAINT MONO (2910 3635);
DISPLAY INVISIBLE (2910 3635);
FORCEPROP 1 LASTPIN (2900 3625) BN 5
J 0
(2888 3633);
DISPLAY 0.680851 (2888 3633);
PAINT GREEN (2888 3633);
FORCEPROP 2 LAST CDS_LIB standard
J 0
(2950 3625);
DISPLAY INVISIBLE (2950 3625);
FORCEPROP 1 LAST BODY_TYPE PLUMBING
J 0
(2950 3675);
DISPLAY 0.872340 (2950 3675);
PAINT GREEN (2950 3675);
DISPLAY INVISIBLE (2950 3675);
FORCEPROP 1 LAST HDL_TAP TRUE
J 0
(3275 3500);
DISPLAY 0.872340 (3275 3500);
DISPLAY INVISIBLE (3275 3500);
FORCEPROP 1 LAST PATH I164
J 0
(2948 3625);
DISPLAY 0.872340 (2948 3625);
PAINT GREEN (2948 3625);
DISPLAY INVISIBLE (2948 3625);
FORCEADD TAP..1
(2950 3825);
FORCEPROP 3 LASTPIN (2900 3825) SIG_NAME M_A_CPU1_SA_DQS_DN<7>
J 0
(2910 3835);
DISPLAY 0.659574 (2910 3835);
PAINT MONO (2910 3835);
DISPLAY INVISIBLE (2910 3835);
FORCEPROP 1 LASTPIN (2900 3825) BN 7
J 0
(2888 3833);
DISPLAY 0.680851 (2888 3833);
PAINT GREEN (2888 3833);
FORCEPROP 2 LAST CDS_LIB standard
J 0
(2950 3825);
DISPLAY INVISIBLE (2950 3825);
FORCEPROP 1 LAST BODY_TYPE PLUMBING
J 0
(2950 3875);
DISPLAY 0.872340 (2950 3875);
PAINT GREEN (2950 3875);
DISPLAY INVISIBLE (2950 3875);
FORCEPROP 1 LAST HDL_TAP TRUE
J 0
(3275 3700);
DISPLAY 0.872340 (3275 3700);
DISPLAY INVISIBLE (3275 3700);
FORCEPROP 1 LAST PATH I165
J 0
(2948 3825);
DISPLAY 0.872340 (2948 3825);
PAINT GREEN (2948 3825);
DISPLAY INVISIBLE (2948 3825);
FORCEADD OFFPAGE..2
(3900 3000);
FORCEPROP 2 LAST $XR1 99 
J 0
(4179 3000);
DISPLAY 0.638298 (4179 3000);
PAINT MONO (4179 3000);
FORCEPROP 2 LAST $XR0 51 
J 0
(4089 3000);
DISPLAY 0.638298 (4089 3000);
PAINT MONO (4089 3000);
FORCEPROP 2 LAST CDS_LIB standard
J 0
(3900 3000);
PAINT MONO (3900 3000);
DISPLAY INVISIBLE (3900 3000);
FORCEPROP 1 LAST OFFPAGE TRUE
J 0
(4225 2875);
DISPLAY 1.170213 (4225 2875);
PAINT GREEN (4225 2875);
DISPLAY INVISIBLE (4225 2875);
FORCEPROP 1 LAST COMMENT_BODY TRUE
J 0
(3855 2905);
DISPLAY 1.170213 (3855 2905);
PAINT GREEN (3855 2905);
DISPLAY INVISIBLE (3855 2905);
FORCEPROP 2 LAST PATH I166
J 0
(4075 3075);
DISPLAY 1.021277 (4075 3075);
DISPLAY INVISIBLE (4075 3075);
FORCEADD OFFPAGE..2
(3900 3050);
FORCEPROP 2 LAST $XR1 99 
J 0
(4179 3050);
DISPLAY 0.638298 (4179 3050);
PAINT MONO (4179 3050);
FORCEPROP 2 LAST $XR0 51 
J 0
(4089 3050);
DISPLAY 0.638298 (4089 3050);
PAINT MONO (4089 3050);
FORCEPROP 2 LAST CDS_LIB standard
J 0
(3900 3050);
PAINT MONO (3900 3050);
DISPLAY INVISIBLE (3900 3050);
FORCEPROP 1 LAST OFFPAGE TRUE
J 0
(4225 2925);
DISPLAY 1.170213 (4225 2925);
PAINT GREEN (4225 2925);
DISPLAY INVISIBLE (4225 2925);
FORCEPROP 1 LAST COMMENT_BODY TRUE
J 0
(3855 2955);
DISPLAY 1.170213 (3855 2955);
PAINT GREEN (3855 2955);
DISPLAY INVISIBLE (3855 2955);
FORCEPROP 2 LAST PATH I167
J 0
(4075 3125);
DISPLAY 1.021277 (4075 3125);
DISPLAY INVISIBLE (4075 3125);
FORCEADD OFFPAGE..3
(850 4100);
FORCEPROP 2 LAST $XR1 99 
J 0
(1154 4100);
DISPLAY 0.638298 (1154 4100);
PAINT MONO (1154 4100);
FORCEPROP 2 LAST $XR0 51 
J 0
(1064 4100);
DISPLAY 0.638298 (1064 4100);
PAINT MONO (1064 4100);
FORCEPROP 2 LAST CDS_LIB standard
J 2
(850 4100);
DISPLAY INVISIBLE (850 4100);
FORCEPROP 1 LAST OFFPAGE TRUE
J 0
(1175 3975);
DISPLAY 0.872340 (1175 3975);
DISPLAY INVISIBLE (1175 3975);
FORCEPROP 1 LAST COMMENT_BODY TRUE
J 0
(800 4000);
DISPLAY 0.872340 (800 4000);
PAINT GREEN (800 4000);
DISPLAY INVISIBLE (800 4000);
FORCEPROP 2 LAST PATH I168
J 0
(1050 4175);
DISPLAY 1.021277 (1050 4175);
DISPLAY INVISIBLE (1050 4175);
FORCEADD TAP..1
(2775 3875);
FORCEPROP 3 LASTPIN (2725 3875) SIG_NAME M_A_CPU1_SA_DQS_DP<7>
J 0
(2735 3885);
DISPLAY 0.659574 (2735 3885);
PAINT MONO (2735 3885);
DISPLAY INVISIBLE (2735 3885);
FORCEPROP 1 LASTPIN (2725 3875) BN 7
J 0
(2713 3883);
DISPLAY 0.680851 (2713 3883);
PAINT GREEN (2713 3883);
FORCEPROP 2 LAST CDS_LIB standard
J 0
(2775 3875);
DISPLAY INVISIBLE (2775 3875);
FORCEPROP 1 LAST BODY_TYPE PLUMBING
J 0
(2775 3925);
DISPLAY 0.872340 (2775 3925);
PAINT GREEN (2775 3925);
DISPLAY INVISIBLE (2775 3925);
FORCEPROP 1 LAST HDL_TAP TRUE
J 0
(3100 3750);
DISPLAY 0.872340 (3100 3750);
DISPLAY INVISIBLE (3100 3750);
FORCEPROP 1 LAST PATH I169
J 0
(2773 3875);
DISPLAY 0.872340 (2773 3875);
PAINT GREEN (2773 3875);
DISPLAY INVISIBLE (2773 3875);
FORCEADD OFFPAGE..1
(-2550 2825);
FORCEPROP 2 LAST $XR0 51 
J 0
(-2771 2825);
DISPLAY 0.638298 (-2771 2825);
PAINT MONO (-2771 2825);
FORCEPROP 2 LAST CDS_LIB standard
J 0
(-2550 2825);
PAINT MONO (-2550 2825);
DISPLAY INVISIBLE (-2550 2825);
FORCEPROP 1 LAST OFFPAGE TRUE
J 0
(-2225 2700);
DISPLAY 0.872340 (-2225 2700);
DISPLAY INVISIBLE (-2225 2700);
FORCEPROP 1 LAST COMMENT_BODY TRUE
J 0
(-2425 2725);
DISPLAY 0.872340 (-2425 2725);
PAINT GREEN (-2425 2725);
DISPLAY INVISIBLE (-2425 2725);
FORCEPROP 2 LAST PATH I17
J 0
(-2500 2900);
DISPLAY 1.021277 (-2500 2900);
DISPLAY INVISIBLE (-2500 2900);
FORCEADD TAP..1
(2775 3975);
FORCEPROP 3 LASTPIN (2725 3975) SIG_NAME M_A_CPU1_SA_DQS_DP<8>
J 0
(2735 3985);
DISPLAY 0.659574 (2735 3985);
PAINT MONO (2735 3985);
DISPLAY INVISIBLE (2735 3985);
FORCEPROP 1 LASTPIN (2725 3975) BN 8
J 0
(2713 3983);
DISPLAY 0.680851 (2713 3983);
PAINT GREEN (2713 3983);
FORCEPROP 2 LAST CDS_LIB standard
J 0
(2775 3975);
DISPLAY INVISIBLE (2775 3975);
FORCEPROP 1 LAST BODY_TYPE PLUMBING
J 0
(2775 4025);
DISPLAY 0.872340 (2775 4025);
PAINT GREEN (2775 4025);
DISPLAY INVISIBLE (2775 4025);
FORCEPROP 1 LAST HDL_TAP TRUE
J 0
(3100 3850);
DISPLAY 0.872340 (3100 3850);
DISPLAY INVISIBLE (3100 3850);
FORCEPROP 1 LAST PATH I170
J 0
(2773 3975);
DISPLAY 0.872340 (2773 3975);
PAINT GREEN (2773 3975);
DISPLAY INVISIBLE (2773 3975);
FORCEADD TAP..1
(2775 4075);
FORCEPROP 3 LASTPIN (2725 4075) SIG_NAME M_A_CPU1_SA_DQS_DP<9>
J 0
(2735 4085);
DISPLAY 0.659574 (2735 4085);
PAINT MONO (2735 4085);
DISPLAY INVISIBLE (2735 4085);
FORCEPROP 1 LASTPIN (2725 4075) BN 9
J 0
(2713 4083);
DISPLAY 0.680851 (2713 4083);
PAINT GREEN (2713 4083);
FORCEPROP 2 LAST CDS_LIB standard
J 0
(2775 4075);
DISPLAY INVISIBLE (2775 4075);
FORCEPROP 1 LAST BODY_TYPE PLUMBING
J 0
(2775 4125);
DISPLAY 0.872340 (2775 4125);
PAINT GREEN (2775 4125);
DISPLAY INVISIBLE (2775 4125);
FORCEPROP 1 LAST HDL_TAP TRUE
J 0
(3100 3950);
DISPLAY 0.872340 (3100 3950);
DISPLAY INVISIBLE (3100 3950);
FORCEPROP 1 LAST PATH I171
J 0
(2773 4075);
DISPLAY 0.872340 (2773 4075);
PAINT GREEN (2773 4075);
DISPLAY INVISIBLE (2773 4075);
FORCEADD TAP..1
(2950 3925);
FORCEPROP 3 LASTPIN (2900 3925) SIG_NAME M_A_CPU1_SA_DQS_DN<8>
J 0
(2910 3935);
DISPLAY 0.659574 (2910 3935);
PAINT MONO (2910 3935);
DISPLAY INVISIBLE (2910 3935);
FORCEPROP 1 LASTPIN (2900 3925) BN 8
J 0
(2888 3933);
DISPLAY 0.680851 (2888 3933);
PAINT GREEN (2888 3933);
FORCEPROP 2 LAST CDS_LIB standard
J 0
(2950 3925);
DISPLAY INVISIBLE (2950 3925);
FORCEPROP 1 LAST BODY_TYPE PLUMBING
J 0
(2950 3975);
DISPLAY 0.872340 (2950 3975);
PAINT GREEN (2950 3975);
DISPLAY INVISIBLE (2950 3975);
FORCEPROP 1 LAST HDL_TAP TRUE
J 0
(3275 3800);
DISPLAY 0.872340 (3275 3800);
DISPLAY INVISIBLE (3275 3800);
FORCEPROP 1 LAST PATH I172
J 0
(2948 3925);
DISPLAY 0.872340 (2948 3925);
PAINT GREEN (2948 3925);
DISPLAY INVISIBLE (2948 3925);
FORCEADD TAP..1
(2950 4025);
FORCEPROP 3 LASTPIN (2900 4025) SIG_NAME M_A_CPU1_SA_DQS_DN<9>
J 0
(2910 4035);
DISPLAY 0.659574 (2910 4035);
PAINT MONO (2910 4035);
DISPLAY INVISIBLE (2910 4035);
FORCEPROP 1 LASTPIN (2900 4025) BN 9
J 0
(2888 4033);
DISPLAY 0.680851 (2888 4033);
PAINT GREEN (2888 4033);
FORCEPROP 2 LAST CDS_LIB standard
J 0
(2950 4025);
DISPLAY INVISIBLE (2950 4025);
FORCEPROP 1 LAST BODY_TYPE PLUMBING
J 0
(2950 4075);
DISPLAY 0.872340 (2950 4075);
PAINT GREEN (2950 4075);
DISPLAY INVISIBLE (2950 4075);
FORCEPROP 1 LAST HDL_TAP TRUE
J 0
(3275 3900);
DISPLAY 0.872340 (3275 3900);
DISPLAY INVISIBLE (3275 3900);
FORCEPROP 1 LAST PATH I173
J 0
(2948 4025);
DISPLAY 0.872340 (2948 4025);
PAINT GREEN (2948 4025);
DISPLAY INVISIBLE (2948 4025);
FORCEADD OFFPAGE..2
(3900 4050);
FORCEPROP 2 LAST $XR1 99 
J 0
(4179 4050);
DISPLAY 0.638298 (4179 4050);
PAINT MONO (4179 4050);
FORCEPROP 2 LAST $XR0 51 
J 0
(4089 4050);
DISPLAY 0.638298 (4089 4050);
PAINT MONO (4089 4050);
FORCEPROP 2 LAST CDS_LIB standard
J 0
(3900 4050);
PAINT MONO (3900 4050);
DISPLAY INVISIBLE (3900 4050);
FORCEPROP 1 LAST OFFPAGE TRUE
J 0
(4225 3925);
DISPLAY 1.170213 (4225 3925);
PAINT GREEN (4225 3925);
DISPLAY INVISIBLE (4225 3925);
FORCEPROP 1 LAST COMMENT_BODY TRUE
J 0
(3855 3955);
DISPLAY 1.170213 (3855 3955);
PAINT GREEN (3855 3955);
DISPLAY INVISIBLE (3855 3955);
FORCEPROP 2 LAST PATH I174
J 0
(4075 4125);
DISPLAY 1.021277 (4075 4125);
DISPLAY INVISIBLE (4075 4125);
FORCEADD OFFPAGE..2
(3900 4100);
FORCEPROP 2 LAST $XR1 99 
J 0
(4179 4100);
DISPLAY 0.638298 (4179 4100);
PAINT MONO (4179 4100);
FORCEPROP 2 LAST $XR0 51 
J 0
(4089 4100);
DISPLAY 0.638298 (4089 4100);
PAINT MONO (4089 4100);
FORCEPROP 2 LAST CDS_LIB standard
J 0
(3900 4100);
PAINT MONO (3900 4100);
DISPLAY INVISIBLE (3900 4100);
FORCEPROP 1 LAST OFFPAGE TRUE
J 0
(4225 3975);
DISPLAY 1.170213 (4225 3975);
PAINT GREEN (4225 3975);
DISPLAY INVISIBLE (4225 3975);
FORCEPROP 1 LAST COMMENT_BODY TRUE
J 0
(3855 4005);
DISPLAY 1.170213 (3855 4005);
PAINT GREEN (3855 4005);
DISPLAY INVISIBLE (3855 4005);
FORCEPROP 2 LAST PATH I175
J 0
(4075 4175);
DISPLAY 1.021277 (4075 4175);
DISPLAY INVISIBLE (4075 4175);
FORCEADD VCC_CORE..1
(4450 4625);
FORCEPROP 3 LASTPIN (4450 4575) SIG_NAME P12V_S3_AUX_CPU1_NVDIMM\g
J 0
(4460 4585);
DISPLAY 0.659574 (4460 4585);
PAINT MONO (4460 4585);
DISPLAY INVISIBLE (4460 4585);
FORCEPROP 1 LAST HDL_POWER P12V_S3_AUX_CPU1_NVDIMM
J 1
(4450 4675);
DISPLAY 1.148936 (4450 4675);
PAINT GREEN (4450 4675);
FORCEPROP 2 LAST CDS_LIB logical_power
J 0
(4450 4625);
PAINT MONO (4450 4625);
DISPLAY INVISIBLE (4450 4625);
FORCEPROP 1 LAST PATH I176
J 0
(4500 4650);
DISPLAY 0.872340 (4500 4650);
PAINT AQUA (4500 4650);
DISPLAY INVISIBLE (4500 4650);
FORCEADD UNIVERSAL_GND..1
(6150 375);
FORCEPROP 3 LASTPIN (6150 425) SIG_NAME GND\g
J 0
(6160 435);
DISPLAY 0.659574 (6160 435);
PAINT MONO (6160 435);
DISPLAY INVISIBLE (6160 435);
FORCEPROP 2 LAST CDS_LIB logical_power
J 0
(6150 375);
PAINT MONO (6150 375);
DISPLAY INVISIBLE (6150 375);
FORCEPROP 1 LAST HDL_POWER GND
J 1
(6175 300);
DISPLAY 0.872340 (6175 300);
PAINT GREEN (6175 300);
DISPLAY INVISIBLE (6175 300);
FORCEPROP 1 LAST PATH I177
J 0
(6225 375);
DISPLAY 0.872340 (6225 375);
PAINT AQUA (6225 375);
DISPLAY INVISIBLE (6225 375);
FORCEADD SCONN288_ADR50017P130CC..2
(1875 3075);
FORCEPROP 1 LAST PART_NUMBER DFHST8FS461
J 0
(1282 4375);
DISPLAY 0.723404 (1282 4375);
PAINT GREEN (1282 4375);
DISPLAY INVISIBLE (1282 4375);
FORCEPROP 1 LAST MATERIAL IO
J 0
(1282 4248);
DISPLAY 0.723404 (1282 4248);
PAINT GREEN (1282 4248);
FORCEPROP 2 LAST PART_TYPE SMLF
J 0
(1293 4528);
DISPLAY 1.021277 (1293 4528);
FORCEPROP 2 LAST VALUE SCONN288_ADR50017-P130CC
J 0
(1293 4478);
DISPLAY 1.021277 (1293 4478);
FORCEPROP 1 LAST LOCATION J17
J 0
(1275 4425);
DISPLAY 0.723404 (1275 4425);
PAINT GREEN (1275 4425);
FORCEPROP 0 LASTPIN (2625 3125) $PN 12
J 0
(2635 3135);
DISPLAY 0.680851 (2635 3135);
PAINT MONO (2635 3135);
FORCEPROP 0 LASTPIN (2625 3175) $PN 11
J 0
(2635 3185);
DISPLAY 0.680851 (2635 3185);
PAINT MONO (2635 3185);
FORCEPROP 0 LASTPIN (2625 2075) $PN 105
J 0
(2635 2085);
DISPLAY 0.680851 (2635 2085);
PAINT MONO (2635 2085);
FORCEPROP 0 LASTPIN (2625 2125) $PN 104
J 0
(2635 2135);
DISPLAY 0.680851 (2635 2135);
PAINT MONO (2635 2135);
FORCEPROP 0 LASTPIN (2625 3225) $PN 23
J 0
(2635 3235);
DISPLAY 0.680851 (2635 3235);
PAINT MONO (2635 3235);
FORCEPROP 0 LASTPIN (2625 3275) $PN 22
J 0
(2635 3285);
DISPLAY 0.680851 (2635 3285);
PAINT MONO (2635 3285);
FORCEPROP 0 LASTPIN (2625 2175) $PN 116
J 0
(2635 2185);
DISPLAY 0.680851 (2635 2185);
PAINT MONO (2635 2185);
FORCEPROP 0 LASTPIN (2625 2225) $PN 115
J 0
(2635 2235);
DISPLAY 0.680851 (2635 2235);
PAINT MONO (2635 2235);
FORCEPROP 0 LASTPIN (2625 3325) $PN 34
J 0
(2635 3335);
DISPLAY 0.680851 (2635 3335);
PAINT MONO (2635 3335);
FORCEPROP 0 LASTPIN (2625 3375) $PN 33
J 0
(2635 3385);
DISPLAY 0.680851 (2635 3385);
PAINT MONO (2635 3385);
FORCEPROP 0 LASTPIN (2625 2275) $PN 127
J 0
(2635 2285);
DISPLAY 0.680851 (2635 2285);
PAINT MONO (2635 2285);
FORCEPROP 0 LASTPIN (2625 2325) $PN 126
J 0
(2635 2335);
DISPLAY 0.680851 (2635 2335);
PAINT MONO (2635 2335);
FORCEPROP 0 LASTPIN (2625 3425) $PN 45
J 0
(2635 3435);
DISPLAY 0.680851 (2635 3435);
PAINT MONO (2635 3435);
FORCEPROP 0 LASTPIN (2625 3475) $PN 44
J 0
(2635 3485);
DISPLAY 0.680851 (2635 3485);
PAINT MONO (2635 3485);
FORCEPROP 0 LASTPIN (2625 2375) $PN 138
J 0
(2635 2385);
DISPLAY 0.680851 (2635 2385);
PAINT MONO (2635 2385);
FORCEPROP 0 LASTPIN (2625 2425) $PN 137
J 0
(2635 2435);
DISPLAY 0.680851 (2635 2435);
PAINT MONO (2635 2435);
FORCEPROP 0 LASTPIN (2625 3525) $PN 56
J 0
(2635 3535);
DISPLAY 0.680851 (2635 3535);
PAINT MONO (2635 3535);
FORCEPROP 0 LASTPIN (2625 3575) $PN 55
J 0
(2635 3585);
DISPLAY 0.680851 (2635 3585);
PAINT MONO (2635 3585);
FORCEPROP 0 LASTPIN (2625 2475) $PN 238
J 0
(2635 2485);
DISPLAY 0.680851 (2635 2485);
PAINT MONO (2635 2485);
FORCEPROP 0 LASTPIN (2625 2525) $PN 239
J 0
(2635 2535);
DISPLAY 0.680851 (2635 2535);
PAINT MONO (2635 2535);
FORCEPROP 0 LASTPIN (2625 3625) $PN 156
J 0
(2635 3635);
DISPLAY 0.680851 (2635 3635);
PAINT MONO (2635 3635);
FORCEPROP 0 LASTPIN (2625 3675) $PN 157
J 0
(2635 3685);
DISPLAY 0.680851 (2635 3685);
PAINT MONO (2635 3685);
FORCEPROP 0 LASTPIN (2625 2575) $PN 249
J 0
(2635 2585);
DISPLAY 0.680851 (2635 2585);
PAINT MONO (2635 2585);
FORCEPROP 0 LASTPIN (2625 2625) $PN 250
J 0
(2635 2635);
DISPLAY 0.680851 (2635 2635);
PAINT MONO (2635 2635);
FORCEPROP 0 LASTPIN (2625 3725) $PN 167
J 0
(2635 3735);
DISPLAY 0.680851 (2635 3735);
PAINT MONO (2635 3735);
FORCEPROP 0 LASTPIN (2625 3775) $PN 168
J 0
(2635 3785);
DISPLAY 0.680851 (2635 3785);
PAINT MONO (2635 3785);
FORCEPROP 0 LASTPIN (2625 2675) $PN 260
J 0
(2635 2685);
DISPLAY 0.680851 (2635 2685);
PAINT MONO (2635 2685);
FORCEPROP 0 LASTPIN (2625 2725) $PN 261
J 0
(2635 2735);
DISPLAY 0.680851 (2635 2735);
PAINT MONO (2635 2735);
FORCEPROP 0 LASTPIN (2625 3825) $PN 178
J 0
(2635 3835);
DISPLAY 0.680851 (2635 3835);
PAINT MONO (2635 3835);
FORCEPROP 0 LASTPIN (2625 3875) $PN 179
J 0
(2635 3885);
DISPLAY 0.680851 (2635 3885);
PAINT MONO (2635 3885);
FORCEPROP 0 LASTPIN (2625 2775) $PN 271
J 0
(2635 2785);
DISPLAY 0.680851 (2635 2785);
PAINT MONO (2635 2785);
FORCEPROP 0 LASTPIN (2625 2825) $PN 272
J 0
(2635 2835);
DISPLAY 0.680851 (2635 2835);
PAINT MONO (2635 2835);
FORCEPROP 0 LASTPIN (2625 3925) $PN 189
J 0
(2635 3935);
DISPLAY 0.680851 (2635 3935);
PAINT MONO (2635 3935);
FORCEPROP 0 LASTPIN (2625 3975) $PN 190
J 0
(2635 3985);
DISPLAY 0.680851 (2635 3985);
PAINT MONO (2635 3985);
FORCEPROP 0 LASTPIN (2625 2875) $PN 282
J 0
(2635 2885);
DISPLAY 0.680851 (2635 2885);
PAINT MONO (2635 2885);
FORCEPROP 0 LASTPIN (2625 2925) $PN 283
J 0
(2635 2935);
DISPLAY 0.680851 (2635 2935);
PAINT MONO (2635 2935);
FORCEPROP 0 LASTPIN (2625 4025) $PN 200
J 0
(2635 4035);
DISPLAY 0.680851 (2635 4035);
PAINT MONO (2635 4035);
FORCEPROP 0 LASTPIN (2625 4075) $PN 201
J 0
(2635 4085);
DISPLAY 0.680851 (2635 4085);
PAINT MONO (2635 4085);
FORCEPROP 0 LASTPIN (2625 2975) $PN 94
J 0
(2635 2985);
DISPLAY 0.680851 (2635 2985);
PAINT MONO (2635 2985);
FORCEPROP 0 LASTPIN (2625 3025) $PN 93
J 0
(2635 3035);
DISPLAY 0.680851 (2635 3035);
PAINT MONO (2635 3035);
FORCEPROP 2 LAST CDS_LIB pure_quanta
J 0
(1875 3075);
DISPLAY INVISIBLE (1875 3075);
FORCEPROP 1 LAST CDS_LMAN_SYM_OUTLINE -600,1150,600,-1150
J 0
(1875 3075);
DISPLAY 0.468085 (1875 3075);
PAINT GREEN (1875 3075);
DISPLAY INVISIBLE (1875 3075);
FORCEPROP 1 LAST NEEDS_NO_SIZE TRUE
J 0
(1875 3075);
DISPLAY 0.723404 (1875 3075);
PAINT GREEN (1875 3075);
DISPLAY INVISIBLE (1875 3075);
FORCEPROP 0 LAST $SEC 2
J 0
(1300 4600);
DISPLAY 0.680851 (1300 4600);
PAINT MONO (1300 4600);
DISPLAY INVISIBLE (1300 4600);
FORCEPROP 0 LAST CDS_SEC 2
J 0
(1300 4600);
DISPLAY 1.021277 (1300 4600);
DISPLAY INVISIBLE (1300 4600);
FORCEPROP 1 LAST PATH I178
J 0
(1875 3075);
DISPLAY 0.723404 (1875 3075);
PAINT GREEN (1875 3075);
DISPLAY INVISIBLE (1875 3075);
FORCEADD Q_RES..1
(-2625 1350);
FORCEPROP 1 LAST PART_NUMBER CS04992FB07
J 0
(-2525 1325);
DISPLAY 0.404255 (-2525 1325);
DISPLAY INVISIBLE (-2525 1325);
FORCEPROP 1 LAST VALUE 49.9
J 2
(-2400 1350);
DISPLAY 0.510638 (-2400 1350);
FORCEPROP 1 LAST MATERIAL CHIP
J 0
(-2850 1325);
DISPLAY 0.404255 (-2850 1325);
FORCEPROP 1 LAST $LOCATION R3891
J 0
(-2875 1350);
DISPLAY 0.638298 (-2875 1350);
FORCEPROP 1 LASTPIN (-2725 1350) $PN 1
J 0
(-2713 1362);
DISPLAY 0.787234 (-2713 1362);
PAINT MONO (-2713 1362);
FORCEPROP 1 LASTPIN (-2525 1350) $PN 2
J 0
(-2563 1362);
DISPLAY 0.787234 (-2563 1362);
PAINT MONO (-2563 1362);
FORCEPROP 2 LAST CDS_LIB pure_quanta
J 0
(-2625 1350);
DISPLAY INVISIBLE (-2625 1350);
FORCEPROP 1 LAST PACK_TYPE 0402LF
J 0
(-2325 1350);
DISPLAY 0.510638 (-2325 1350);
DISPLAY INVISIBLE (-2325 1350);
FORCEPROP 1 LAST TOLERANCE 1%
J 0
(-2400 1350);
DISPLAY 0.510638 (-2400 1350);
DISPLAY INVISIBLE (-2400 1350);
FORCEPROP 1 LAST WATTAGE 1/16W
J 2
(-2325 1300);
DISPLAY 0.404255 (-2325 1300);
DISPLAY INVISIBLE (-2325 1300);
FORCEPROP 0 LAST CDS_LOCATION R3891
J 0
(-2775 1400);
DISPLAY 1.021277 (-2775 1400);
DISPLAY INVISIBLE (-2775 1400);
FORCEPROP 0 LAST $SEC 1
J 0
(-2775 1400);
DISPLAY 0.680851 (-2775 1400);
PAINT MONO (-2775 1400);
DISPLAY INVISIBLE (-2775 1400);
FORCEPROP 0 LAST CDS_SEC 1
J 0
(-2775 1400);
DISPLAY 1.021277 (-2775 1400);
DISPLAY INVISIBLE (-2775 1400);
FORCEPROP 1 LAST PATH I179
J 0
(-2675 1500);
DISPLAY 0.978723 (-2675 1500);
PAINT WHITE (-2675 1500);
DISPLAY INVISIBLE (-2675 1500);
FORCEADD OFFPAGE..1
(-2550 3075);
FORCEPROP 2 LAST $XR0 51 
J 0
(-2771 3075);
DISPLAY 0.638298 (-2771 3075);
PAINT MONO (-2771 3075);
FORCEPROP 2 LAST CDS_LIB standard
J 0
(-2550 3075);
PAINT MONO (-2550 3075);
DISPLAY INVISIBLE (-2550 3075);
FORCEPROP 1 LAST OFFPAGE TRUE
J 0
(-2225 2950);
DISPLAY 0.872340 (-2225 2950);
DISPLAY INVISIBLE (-2225 2950);
FORCEPROP 1 LAST COMMENT_BODY TRUE
J 0
(-2425 2975);
DISPLAY 0.872340 (-2425 2975);
PAINT GREEN (-2425 2975);
DISPLAY INVISIBLE (-2425 2975);
FORCEPROP 2 LAST PATH I18
J 0
(-2500 3150);
DISPLAY 1.021277 (-2500 3150);
DISPLAY INVISIBLE (-2500 3150);
FORCEADD OFFPAGE..1
(-1350 1300);
FORCEPROP 2 LAST $XR7 105 
J 0
(-2442 1300);
DISPLAY 0.638298 (-2442 1300);
PAINT MONO (-2442 1300);
FORCEPROP 2 LAST $XR6 104 
J 0
(-2322 1300);
DISPLAY 0.638298 (-2322 1300);
PAINT MONO (-2322 1300);
FORCEPROP 2 LAST $XR5 103 
J 0
(-2202 1300);
DISPLAY 0.638298 (-2202 1300);
PAINT MONO (-2202 1300);
FORCEPROP 2 LAST $XR4 102 
J 0
(-2082 1300);
DISPLAY 0.638298 (-2082 1300);
PAINT MONO (-2082 1300);
FORCEPROP 2 LAST $XR3 101 
J 0
(-1962 1300);
DISPLAY 0.638298 (-1962 1300);
PAINT MONO (-1962 1300);
FORCEPROP 2 LAST $XR2 100 
J 0
(-1842 1300);
DISPLAY 0.638298 (-1842 1300);
PAINT MONO (-1842 1300);
FORCEPROP 2 LAST $XR1 99 
J 0
(-1722 1300);
DISPLAY 0.638298 (-1722 1300);
PAINT MONO (-1722 1300);
FORCEPROP 2 LAST $XR0 230 
J 0
(-1632 1300);
DISPLAY 0.638298 (-1632 1300);
PAINT MONO (-1632 1300);
FORCEPROP 2 LAST CDS_LIB standard
J 2
(-1350 1300);
DISPLAY INVISIBLE (-1350 1300);
FORCEPROP 1 LAST OFFPAGE TRUE
J 0
(-1025 1175);
DISPLAY 0.872340 (-1025 1175);
DISPLAY INVISIBLE (-1025 1175);
FORCEPROP 1 LAST COMMENT_BODY TRUE
J 0
(-1225 1200);
DISPLAY 0.872340 (-1225 1200);
PAINT GREEN (-1225 1200);
DISPLAY INVISIBLE (-1225 1200);
FORCEPROP 2 LAST PATH I180
J 2
(-1525 1375);
DISPLAY 1.021277 (-1525 1375);
DISPLAY INVISIBLE (-1525 1375);
FORCEADD OFFPAGE..1
(-2550 2925);
FORCEPROP 2 LAST $XR0 51 
J 0
(-2771 2925);
DISPLAY 0.638298 (-2771 2925);
PAINT MONO (-2771 2925);
FORCEPROP 2 LAST CDS_LIB standard
J 0
(-2550 2925);
PAINT MONO (-2550 2925);
DISPLAY INVISIBLE (-2550 2925);
FORCEPROP 1 LAST OFFPAGE TRUE
J 0
(-2225 2800);
DISPLAY 0.872340 (-2225 2800);
DISPLAY INVISIBLE (-2225 2800);
FORCEPROP 1 LAST COMMENT_BODY TRUE
J 0
(-2425 2825);
DISPLAY 0.872340 (-2425 2825);
PAINT GREEN (-2425 2825);
DISPLAY INVISIBLE (-2425 2825);
FORCEPROP 2 LAST PATH I19
J 0
(-2500 3000);
DISPLAY 1.021277 (-2500 3000);
DISPLAY INVISIBLE (-2500 3000);
FORCEADD OFFPAGE..2
R 2
(-2550 125);
FORCEPROP 2 LAST $XR0 98 
J 0
(-2774 125);
DISPLAY 0.638298 (-2774 125);
PAINT MONO (-2774 125);
FORCEPROP 2 LAST CDS_LIB standard
J 0
(-2550 125);
PAINT MONO (-2550 125);
DISPLAY INVISIBLE (-2550 125);
FORCEPROP 1 LAST OFFPAGE TRUE
J 2
(-2875 0);
DISPLAY 0.872340 (-2875 0);
DISPLAY INVISIBLE (-2875 0);
FORCEPROP 1 LAST COMMENT_BODY TRUE
J 2
(-2505 30);
DISPLAY 0.872340 (-2505 30);
PAINT GREEN (-2505 30);
DISPLAY INVISIBLE (-2505 30);
FORCEPROP 2 LAST PATH I2
J 0
(-2500 200);
DISPLAY 1.021277 (-2500 200);
DISPLAY INVISIBLE (-2500 200);
FORCEADD OFFPAGE..1
(-2550 2975);
FORCEPROP 2 LAST $XR0 51 
J 0
(-2771 2975);
DISPLAY 0.638298 (-2771 2975);
PAINT MONO (-2771 2975);
FORCEPROP 2 LAST CDS_LIB standard
J 0
(-2550 2975);
PAINT MONO (-2550 2975);
DISPLAY INVISIBLE (-2550 2975);
FORCEPROP 1 LAST OFFPAGE TRUE
J 0
(-2225 2850);
DISPLAY 0.872340 (-2225 2850);
DISPLAY INVISIBLE (-2225 2850);
FORCEPROP 1 LAST COMMENT_BODY TRUE
J 0
(-2425 2875);
DISPLAY 0.872340 (-2425 2875);
PAINT GREEN (-2425 2875);
DISPLAY INVISIBLE (-2425 2875);
FORCEPROP 2 LAST PATH I20
J 0
(-2500 3050);
DISPLAY 1.021277 (-2500 3050);
DISPLAY INVISIBLE (-2500 3050);
FORCEADD OFFPAGE..1
(-2550 3125);
FORCEPROP 2 LAST $XR0 51 
J 0
(-2771 3125);
DISPLAY 0.638298 (-2771 3125);
PAINT MONO (-2771 3125);
FORCEPROP 2 LAST CDS_LIB standard
J 0
(-2550 3125);
PAINT MONO (-2550 3125);
DISPLAY INVISIBLE (-2550 3125);
FORCEPROP 1 LAST OFFPAGE TRUE
J 0
(-2225 3000);
DISPLAY 0.872340 (-2225 3000);
DISPLAY INVISIBLE (-2225 3000);
FORCEPROP 1 LAST COMMENT_BODY TRUE
J 0
(-2425 3025);
DISPLAY 0.872340 (-2425 3025);
PAINT GREEN (-2425 3025);
DISPLAY INVISIBLE (-2425 3025);
FORCEPROP 2 LAST PATH I21
J 0
(-2500 3200);
DISPLAY 1.021277 (-2500 3200);
DISPLAY INVISIBLE (-2500 3200);
FORCEADD OFFPAGE..1
(-2550 3225);
FORCEPROP 2 LAST $XR1 99 
J 0
(-2861 3225);
DISPLAY 0.638298 (-2861 3225);
PAINT MONO (-2861 3225);
FORCEPROP 2 LAST $XR0 51 
J 0
(-2771 3225);
DISPLAY 0.638298 (-2771 3225);
PAINT MONO (-2771 3225);
FORCEPROP 2 LAST CDS_LIB standard
J 0
(-2550 3225);
PAINT MONO (-2550 3225);
DISPLAY INVISIBLE (-2550 3225);
FORCEPROP 1 LAST OFFPAGE TRUE
J 0
(-2225 3100);
DISPLAY 0.872340 (-2225 3100);
DISPLAY INVISIBLE (-2225 3100);
FORCEPROP 1 LAST COMMENT_BODY TRUE
J 0
(-2425 3125);
DISPLAY 0.872340 (-2425 3125);
PAINT GREEN (-2425 3125);
DISPLAY INVISIBLE (-2425 3125);
FORCEPROP 2 LAST PATH I22
J 0
(-2500 3300);
DISPLAY 1.021277 (-2500 3300);
DISPLAY INVISIBLE (-2500 3300);
FORCEADD OFFPAGE..1
(-2550 3275);
FORCEPROP 2 LAST $XR1 99 
J 0
(-2861 3275);
DISPLAY 0.638298 (-2861 3275);
PAINT MONO (-2861 3275);
FORCEPROP 2 LAST $XR0 51 
J 0
(-2771 3275);
DISPLAY 0.638298 (-2771 3275);
PAINT MONO (-2771 3275);
FORCEPROP 2 LAST CDS_LIB standard
J 0
(-2550 3275);
PAINT MONO (-2550 3275);
DISPLAY INVISIBLE (-2550 3275);
FORCEPROP 1 LAST OFFPAGE TRUE
J 0
(-2225 3150);
DISPLAY 0.872340 (-2225 3150);
DISPLAY INVISIBLE (-2225 3150);
FORCEPROP 1 LAST COMMENT_BODY TRUE
J 0
(-2425 3175);
DISPLAY 0.872340 (-2425 3175);
PAINT GREEN (-2425 3175);
DISPLAY INVISIBLE (-2425 3175);
FORCEPROP 2 LAST PATH I23
J 0
(-2500 3350);
DISPLAY 1.021277 (-2500 3350);
DISPLAY INVISIBLE (-2500 3350);
FORCEADD OFFPAGE..1
(-2550 3700);
FORCEPROP 2 LAST $XR1 99 
J 0
(-2861 3700);
DISPLAY 0.638298 (-2861 3700);
PAINT MONO (-2861 3700);
FORCEPROP 2 LAST $XR0 51 
J 0
(-2771 3700);
DISPLAY 0.638298 (-2771 3700);
PAINT MONO (-2771 3700);
FORCEPROP 2 LAST CDS_LIB standard
J 0
(-2550 3700);
PAINT MONO (-2550 3700);
DISPLAY INVISIBLE (-2550 3700);
FORCEPROP 1 LAST OFFPAGE TRUE
J 0
(-2225 3575);
DISPLAY 0.872340 (-2225 3575);
DISPLAY INVISIBLE (-2225 3575);
FORCEPROP 1 LAST COMMENT_BODY TRUE
J 0
(-2425 3600);
DISPLAY 0.872340 (-2425 3600);
PAINT GREEN (-2425 3600);
DISPLAY INVISIBLE (-2425 3600);
FORCEPROP 2 LAST PATH I24
J 0
(-2500 3775);
DISPLAY 1.021277 (-2500 3775);
DISPLAY INVISIBLE (-2500 3775);
FORCEADD TAP..1
R 2
(-1625 1925);
FORCEPROP 3 LASTPIN (-1575 1925) SIG_NAME M_A_CPU1_SB_CB<1>
J 0
(-1565 1935);
DISPLAY 0.659574 (-1565 1935);
PAINT MONO (-1565 1935);
DISPLAY INVISIBLE (-1565 1935);
FORCEPROP 1 LASTPIN (-1575 1925) BN 1
J 2
(-1563 1933);
DISPLAY 0.680851 (-1563 1933);
PAINT GREEN (-1563 1933);
FORCEPROP 2 LAST CDS_LIB standard
J 0
(-1625 1925);
DISPLAY INVISIBLE (-1625 1925);
FORCEPROP 1 LAST BODY_TYPE PLUMBING
J 2
(-1625 1975);
DISPLAY 0.872340 (-1625 1975);
PAINT GREEN (-1625 1975);
DISPLAY INVISIBLE (-1625 1975);
FORCEPROP 1 LAST HDL_TAP TRUE
J 2
(-1950 1800);
DISPLAY 0.872340 (-1950 1800);
DISPLAY INVISIBLE (-1950 1800);
FORCEPROP 1 LAST PATH I25
J 2
(-1623 1925);
DISPLAY 0.872340 (-1623 1925);
PAINT GREEN (-1623 1925);
DISPLAY INVISIBLE (-1623 1925);
FORCEADD TAP..1
R 2
(-1625 1875);
FORCEPROP 3 LASTPIN (-1575 1875) SIG_NAME M_A_CPU1_SB_CB<0>
J 0
(-1565 1885);
DISPLAY 0.659574 (-1565 1885);
PAINT MONO (-1565 1885);
DISPLAY INVISIBLE (-1565 1885);
FORCEPROP 1 LASTPIN (-1575 1875) BN 0
J 2
(-1563 1883);
DISPLAY 0.680851 (-1563 1883);
PAINT GREEN (-1563 1883);
FORCEPROP 2 LAST CDS_LIB standard
J 0
(-1625 1875);
PAINT MONO (-1625 1875);
DISPLAY INVISIBLE (-1625 1875);
FORCEPROP 1 LAST BODY_TYPE PLUMBING
J 2
(-1625 1925);
DISPLAY 0.872340 (-1625 1925);
PAINT GREEN (-1625 1925);
DISPLAY INVISIBLE (-1625 1925);
FORCEPROP 1 LAST HDL_TAP TRUE
J 2
(-1950 1750);
DISPLAY 0.872340 (-1950 1750);
DISPLAY INVISIBLE (-1950 1750);
FORCEPROP 1 LAST PATH I26
J 2
(-1623 1875);
DISPLAY 0.872340 (-1623 1875);
PAINT GREEN (-1623 1875);
DISPLAY INVISIBLE (-1623 1875);
FORCEADD TAP..1
R 2
(-1625 1975);
FORCEPROP 3 LASTPIN (-1575 1975) SIG_NAME M_A_CPU1_SB_CB<2>
J 0
(-1565 1985);
DISPLAY 0.659574 (-1565 1985);
PAINT MONO (-1565 1985);
DISPLAY INVISIBLE (-1565 1985);
FORCEPROP 1 LASTPIN (-1575 1975) BN 2
J 2
(-1563 1983);
DISPLAY 0.680851 (-1563 1983);
PAINT GREEN (-1563 1983);
FORCEPROP 2 LAST CDS_LIB standard
J 0
(-1625 1975);
DISPLAY INVISIBLE (-1625 1975);
FORCEPROP 1 LAST BODY_TYPE PLUMBING
J 2
(-1625 2025);
DISPLAY 0.872340 (-1625 2025);
PAINT GREEN (-1625 2025);
DISPLAY INVISIBLE (-1625 2025);
FORCEPROP 1 LAST HDL_TAP TRUE
J 2
(-1950 1850);
DISPLAY 0.872340 (-1950 1850);
DISPLAY INVISIBLE (-1950 1850);
FORCEPROP 1 LAST PATH I27
J 2
(-1623 1975);
DISPLAY 0.872340 (-1623 1975);
PAINT GREEN (-1623 1975);
DISPLAY INVISIBLE (-1623 1975);
FORCEADD TAP..1
R 2
(-1625 2025);
FORCEPROP 3 LASTPIN (-1575 2025) SIG_NAME M_A_CPU1_SB_CB<3>
J 0
(-1565 2035);
DISPLAY 0.659574 (-1565 2035);
PAINT MONO (-1565 2035);
DISPLAY INVISIBLE (-1565 2035);
FORCEPROP 1 LASTPIN (-1575 2025) BN 3
J 2
(-1563 2033);
DISPLAY 0.680851 (-1563 2033);
PAINT GREEN (-1563 2033);
FORCEPROP 2 LAST CDS_LIB standard
J 0
(-1625 2025);
DISPLAY INVISIBLE (-1625 2025);
FORCEPROP 1 LAST BODY_TYPE PLUMBING
J 2
(-1625 2075);
DISPLAY 0.872340 (-1625 2075);
PAINT GREEN (-1625 2075);
DISPLAY INVISIBLE (-1625 2075);
FORCEPROP 1 LAST HDL_TAP TRUE
J 2
(-1950 1900);
DISPLAY 0.872340 (-1950 1900);
DISPLAY INVISIBLE (-1950 1900);
FORCEPROP 1 LAST PATH I28
J 2
(-1623 2025);
DISPLAY 0.872340 (-1623 2025);
PAINT GREEN (-1623 2025);
DISPLAY INVISIBLE (-1623 2025);
FORCEADD TAP..1
R 2
(-1625 2075);
FORCEPROP 3 LASTPIN (-1575 2075) SIG_NAME M_A_CPU1_SB_CB<4>
J 0
(-1565 2085);
DISPLAY 0.659574 (-1565 2085);
PAINT MONO (-1565 2085);
DISPLAY INVISIBLE (-1565 2085);
FORCEPROP 1 LASTPIN (-1575 2075) BN 4
J 2
(-1563 2083);
DISPLAY 0.680851 (-1563 2083);
PAINT GREEN (-1563 2083);
FORCEPROP 2 LAST CDS_LIB standard
J 0
(-1625 2075);
DISPLAY INVISIBLE (-1625 2075);
FORCEPROP 1 LAST BODY_TYPE PLUMBING
J 2
(-1625 2125);
DISPLAY 0.872340 (-1625 2125);
PAINT GREEN (-1625 2125);
DISPLAY INVISIBLE (-1625 2125);
FORCEPROP 1 LAST HDL_TAP TRUE
J 2
(-1950 1950);
DISPLAY 0.872340 (-1950 1950);
DISPLAY INVISIBLE (-1950 1950);
FORCEPROP 1 LAST PATH I29
J 2
(-1623 2075);
DISPLAY 0.872340 (-1623 2075);
PAINT GREEN (-1623 2075);
DISPLAY INVISIBLE (-1623 2075);
FORCEADD OFFPAGE..2
R 2
(-2550 625);
FORCEPROP 2 LAST $XR0 51 
J 0
(-2774 625);
DISPLAY 0.638298 (-2774 625);
PAINT MONO (-2774 625);
FORCEPROP 2 LAST CDS_LIB standard
J 0
(-2550 625);
PAINT MONO (-2550 625);
DISPLAY INVISIBLE (-2550 625);
FORCEPROP 1 LAST OFFPAGE TRUE
J 2
(-2875 500);
DISPLAY 0.872340 (-2875 500);
DISPLAY INVISIBLE (-2875 500);
FORCEPROP 1 LAST COMMENT_BODY TRUE
J 2
(-2505 530);
DISPLAY 0.872340 (-2505 530);
PAINT GREEN (-2505 530);
DISPLAY INVISIBLE (-2505 530);
FORCEPROP 2 LAST PATH I3
J 0
(-2500 700);
DISPLAY 1.021277 (-2500 700);
DISPLAY INVISIBLE (-2500 700);
FORCEADD TAP..1
R 2
(-1625 2175);
FORCEPROP 3 LASTPIN (-1575 2175) SIG_NAME M_A_CPU1_SB_CB<6>
J 0
(-1565 2185);
DISPLAY 0.659574 (-1565 2185);
PAINT MONO (-1565 2185);
DISPLAY INVISIBLE (-1565 2185);
FORCEPROP 1 LASTPIN (-1575 2175) BN 6
J 2
(-1563 2183);
DISPLAY 0.680851 (-1563 2183);
PAINT GREEN (-1563 2183);
FORCEPROP 2 LAST CDS_LIB standard
J 0
(-1625 2175);
DISPLAY INVISIBLE (-1625 2175);
FORCEPROP 1 LAST BODY_TYPE PLUMBING
J 2
(-1625 2225);
DISPLAY 0.872340 (-1625 2225);
PAINT GREEN (-1625 2225);
DISPLAY INVISIBLE (-1625 2225);
FORCEPROP 1 LAST HDL_TAP TRUE
J 2
(-1950 2050);
DISPLAY 0.872340 (-1950 2050);
DISPLAY INVISIBLE (-1950 2050);
FORCEPROP 1 LAST PATH I30
J 2
(-1623 2175);
DISPLAY 0.872340 (-1623 2175);
PAINT GREEN (-1623 2175);
DISPLAY INVISIBLE (-1623 2175);
FORCEADD TAP..1
R 2
(-1625 2125);
FORCEPROP 3 LASTPIN (-1575 2125) SIG_NAME M_A_CPU1_SB_CB<5>
J 0
(-1565 2135);
DISPLAY 0.659574 (-1565 2135);
PAINT MONO (-1565 2135);
DISPLAY INVISIBLE (-1565 2135);
FORCEPROP 1 LASTPIN (-1575 2125) BN 5
J 2
(-1563 2133);
DISPLAY 0.680851 (-1563 2133);
PAINT GREEN (-1563 2133);
FORCEPROP 2 LAST CDS_LIB standard
J 0
(-1625 2125);
DISPLAY INVISIBLE (-1625 2125);
FORCEPROP 1 LAST BODY_TYPE PLUMBING
J 2
(-1625 2175);
DISPLAY 0.872340 (-1625 2175);
PAINT GREEN (-1625 2175);
DISPLAY INVISIBLE (-1625 2175);
FORCEPROP 1 LAST HDL_TAP TRUE
J 2
(-1950 2000);
DISPLAY 0.872340 (-1950 2000);
DISPLAY INVISIBLE (-1950 2000);
FORCEPROP 1 LAST PATH I31
J 2
(-1623 2125);
DISPLAY 0.872340 (-1623 2125);
PAINT GREEN (-1623 2125);
DISPLAY INVISIBLE (-1623 2125);
FORCEADD TAP..1
R 2
(-1625 2225);
FORCEPROP 3 LASTPIN (-1575 2225) SIG_NAME M_A_CPU1_SB_CB<7>
J 0
(-1565 2235);
DISPLAY 0.659574 (-1565 2235);
PAINT MONO (-1565 2235);
DISPLAY INVISIBLE (-1565 2235);
FORCEPROP 1 LASTPIN (-1575 2225) BN 7
J 2
(-1563 2233);
DISPLAY 0.680851 (-1563 2233);
PAINT GREEN (-1563 2233);
FORCEPROP 2 LAST CDS_LIB standard
J 0
(-1625 2225);
DISPLAY INVISIBLE (-1625 2225);
FORCEPROP 1 LAST BODY_TYPE PLUMBING
J 2
(-1625 2275);
DISPLAY 0.872340 (-1625 2275);
PAINT GREEN (-1625 2275);
DISPLAY INVISIBLE (-1625 2275);
FORCEPROP 1 LAST HDL_TAP TRUE
J 2
(-1950 2100);
DISPLAY 0.872340 (-1950 2100);
DISPLAY INVISIBLE (-1950 2100);
FORCEPROP 1 LAST PATH I32
J 2
(-1623 2225);
DISPLAY 0.872340 (-1623 2225);
PAINT GREEN (-1623 2225);
DISPLAY INVISIBLE (-1623 2225);
FORCEADD TAP..1
R 2
(-1625 2325);
FORCEPROP 3 LASTPIN (-1575 2325) SIG_NAME M_A_CPU1_SA_CB<0>
J 0
(-1565 2335);
DISPLAY 0.659574 (-1565 2335);
PAINT MONO (-1565 2335);
DISPLAY INVISIBLE (-1565 2335);
FORCEPROP 1 LASTPIN (-1575 2325) BN 0
J 2
(-1563 2333);
DISPLAY 0.680851 (-1563 2333);
PAINT GREEN (-1563 2333);
FORCEPROP 2 LAST CDS_LIB standard
J 0
(-1625 2325);
PAINT MONO (-1625 2325);
DISPLAY INVISIBLE (-1625 2325);
FORCEPROP 1 LAST BODY_TYPE PLUMBING
J 2
(-1625 2375);
DISPLAY 0.872340 (-1625 2375);
PAINT GREEN (-1625 2375);
DISPLAY INVISIBLE (-1625 2375);
FORCEPROP 1 LAST HDL_TAP TRUE
J 2
(-1950 2200);
DISPLAY 0.872340 (-1950 2200);
DISPLAY INVISIBLE (-1950 2200);
FORCEPROP 1 LAST PATH I33
J 2
(-1623 2325);
DISPLAY 0.872340 (-1623 2325);
PAINT GREEN (-1623 2325);
DISPLAY INVISIBLE (-1623 2325);
FORCEADD TAP..1
R 2
(-1625 2375);
FORCEPROP 3 LASTPIN (-1575 2375) SIG_NAME M_A_CPU1_SA_CB<1>
J 0
(-1565 2385);
DISPLAY 0.659574 (-1565 2385);
PAINT MONO (-1565 2385);
DISPLAY INVISIBLE (-1565 2385);
FORCEPROP 1 LASTPIN (-1575 2375) BN 1
J 2
(-1563 2383);
DISPLAY 0.680851 (-1563 2383);
PAINT GREEN (-1563 2383);
FORCEPROP 2 LAST CDS_LIB standard
J 0
(-1625 2375);
DISPLAY INVISIBLE (-1625 2375);
FORCEPROP 1 LAST BODY_TYPE PLUMBING
J 2
(-1625 2425);
DISPLAY 0.872340 (-1625 2425);
PAINT GREEN (-1625 2425);
DISPLAY INVISIBLE (-1625 2425);
FORCEPROP 1 LAST HDL_TAP TRUE
J 2
(-1950 2250);
DISPLAY 0.872340 (-1950 2250);
DISPLAY INVISIBLE (-1950 2250);
FORCEPROP 1 LAST PATH I34
J 2
(-1623 2375);
DISPLAY 0.872340 (-1623 2375);
PAINT GREEN (-1623 2375);
DISPLAY INVISIBLE (-1623 2375);
FORCEADD TAP..1
R 2
(-1625 2425);
FORCEPROP 3 LASTPIN (-1575 2425) SIG_NAME M_A_CPU1_SA_CB<2>
J 0
(-1565 2435);
DISPLAY 0.659574 (-1565 2435);
PAINT MONO (-1565 2435);
DISPLAY INVISIBLE (-1565 2435);
FORCEPROP 1 LASTPIN (-1575 2425) BN 2
J 2
(-1563 2433);
DISPLAY 0.680851 (-1563 2433);
PAINT GREEN (-1563 2433);
FORCEPROP 2 LAST CDS_LIB standard
J 0
(-1625 2425);
DISPLAY INVISIBLE (-1625 2425);
FORCEPROP 1 LAST BODY_TYPE PLUMBING
J 2
(-1625 2475);
DISPLAY 0.872340 (-1625 2475);
PAINT GREEN (-1625 2475);
DISPLAY INVISIBLE (-1625 2475);
FORCEPROP 1 LAST HDL_TAP TRUE
J 2
(-1950 2300);
DISPLAY 0.872340 (-1950 2300);
DISPLAY INVISIBLE (-1950 2300);
FORCEPROP 1 LAST PATH I35
J 2
(-1623 2425);
DISPLAY 0.872340 (-1623 2425);
PAINT GREEN (-1623 2425);
DISPLAY INVISIBLE (-1623 2425);
FORCEADD TAP..1
R 2
(-1625 2475);
FORCEPROP 3 LASTPIN (-1575 2475) SIG_NAME M_A_CPU1_SA_CB<3>
J 0
(-1565 2485);
DISPLAY 0.659574 (-1565 2485);
PAINT MONO (-1565 2485);
DISPLAY INVISIBLE (-1565 2485);
FORCEPROP 1 LASTPIN (-1575 2475) BN 3
J 2
(-1563 2483);
DISPLAY 0.680851 (-1563 2483);
PAINT GREEN (-1563 2483);
FORCEPROP 2 LAST CDS_LIB standard
J 0
(-1625 2475);
DISPLAY INVISIBLE (-1625 2475);
FORCEPROP 1 LAST BODY_TYPE PLUMBING
J 2
(-1625 2525);
DISPLAY 0.872340 (-1625 2525);
PAINT GREEN (-1625 2525);
DISPLAY INVISIBLE (-1625 2525);
FORCEPROP 1 LAST HDL_TAP TRUE
J 2
(-1950 2350);
DISPLAY 0.872340 (-1950 2350);
DISPLAY INVISIBLE (-1950 2350);
FORCEPROP 1 LAST PATH I36
J 2
(-1623 2475);
DISPLAY 0.872340 (-1623 2475);
PAINT GREEN (-1623 2475);
DISPLAY INVISIBLE (-1623 2475);
FORCEADD TAP..1
R 2
(-1625 2525);
FORCEPROP 3 LASTPIN (-1575 2525) SIG_NAME M_A_CPU1_SA_CB<4>
J 0
(-1565 2535);
DISPLAY 0.659574 (-1565 2535);
PAINT MONO (-1565 2535);
DISPLAY INVISIBLE (-1565 2535);
FORCEPROP 1 LASTPIN (-1575 2525) BN 4
J 2
(-1563 2533);
DISPLAY 0.680851 (-1563 2533);
PAINT GREEN (-1563 2533);
FORCEPROP 2 LAST CDS_LIB standard
J 0
(-1625 2525);
DISPLAY INVISIBLE (-1625 2525);
FORCEPROP 1 LAST BODY_TYPE PLUMBING
J 2
(-1625 2575);
DISPLAY 0.872340 (-1625 2575);
PAINT GREEN (-1625 2575);
DISPLAY INVISIBLE (-1625 2575);
FORCEPROP 1 LAST HDL_TAP TRUE
J 2
(-1950 2400);
DISPLAY 0.872340 (-1950 2400);
DISPLAY INVISIBLE (-1950 2400);
FORCEPROP 1 LAST PATH I37
J 2
(-1623 2525);
DISPLAY 0.872340 (-1623 2525);
PAINT GREEN (-1623 2525);
DISPLAY INVISIBLE (-1623 2525);
FORCEADD TAP..1
R 2
(-1625 2575);
FORCEPROP 3 LASTPIN (-1575 2575) SIG_NAME M_A_CPU1_SA_CB<5>
J 0
(-1565 2585);
DISPLAY 0.659574 (-1565 2585);
PAINT MONO (-1565 2585);
DISPLAY INVISIBLE (-1565 2585);
FORCEPROP 1 LASTPIN (-1575 2575) BN 5
J 2
(-1563 2583);
DISPLAY 0.680851 (-1563 2583);
PAINT GREEN (-1563 2583);
FORCEPROP 2 LAST CDS_LIB standard
J 0
(-1625 2575);
DISPLAY INVISIBLE (-1625 2575);
FORCEPROP 1 LAST BODY_TYPE PLUMBING
J 2
(-1625 2625);
DISPLAY 0.872340 (-1625 2625);
PAINT GREEN (-1625 2625);
DISPLAY INVISIBLE (-1625 2625);
FORCEPROP 1 LAST HDL_TAP TRUE
J 2
(-1950 2450);
DISPLAY 0.872340 (-1950 2450);
DISPLAY INVISIBLE (-1950 2450);
FORCEPROP 1 LAST PATH I38
J 2
(-1623 2575);
DISPLAY 0.872340 (-1623 2575);
PAINT GREEN (-1623 2575);
DISPLAY INVISIBLE (-1623 2575);
FORCEADD TAP..1
R 2
(-1625 2675);
FORCEPROP 3 LASTPIN (-1575 2675) SIG_NAME M_A_CPU1_SA_CB<7>
J 0
(-1565 2685);
DISPLAY 0.659574 (-1565 2685);
PAINT MONO (-1565 2685);
DISPLAY INVISIBLE (-1565 2685);
FORCEPROP 1 LASTPIN (-1575 2675) BN 7
J 2
(-1563 2683);
DISPLAY 0.680851 (-1563 2683);
PAINT GREEN (-1563 2683);
FORCEPROP 2 LAST CDS_LIB standard
J 0
(-1625 2675);
DISPLAY INVISIBLE (-1625 2675);
FORCEPROP 1 LAST BODY_TYPE PLUMBING
J 2
(-1625 2725);
DISPLAY 0.872340 (-1625 2725);
PAINT GREEN (-1625 2725);
DISPLAY INVISIBLE (-1625 2725);
FORCEPROP 1 LAST HDL_TAP TRUE
J 2
(-1950 2550);
DISPLAY 0.872340 (-1950 2550);
DISPLAY INVISIBLE (-1950 2550);
FORCEPROP 1 LAST PATH I39
J 2
(-1623 2675);
DISPLAY 0.872340 (-1623 2675);
PAINT GREEN (-1623 2675);
DISPLAY INVISIBLE (-1623 2675);
FORCEADD OFFPAGE..2
R 2
(-2550 675);
FORCEPROP 2 LAST $XR0 51 
J 0
(-2774 675);
DISPLAY 0.638298 (-2774 675);
PAINT MONO (-2774 675);
FORCEPROP 2 LAST CDS_LIB standard
J 0
(-2550 675);
PAINT MONO (-2550 675);
DISPLAY INVISIBLE (-2550 675);
FORCEPROP 1 LAST OFFPAGE TRUE
J 2
(-2875 550);
DISPLAY 0.872340 (-2875 550);
DISPLAY INVISIBLE (-2875 550);
FORCEPROP 1 LAST COMMENT_BODY TRUE
J 2
(-2505 580);
DISPLAY 0.872340 (-2505 580);
PAINT GREEN (-2505 580);
DISPLAY INVISIBLE (-2505 580);
FORCEPROP 2 LAST PATH I4
J 0
(-2500 750);
DISPLAY 1.021277 (-2500 750);
DISPLAY INVISIBLE (-2500 750);
FORCEADD TAP..1
R 2
(-1625 2625);
FORCEPROP 3 LASTPIN (-1575 2625) SIG_NAME M_A_CPU1_SA_CB<6>
J 0
(-1565 2635);
DISPLAY 0.659574 (-1565 2635);
PAINT MONO (-1565 2635);
DISPLAY INVISIBLE (-1565 2635);
FORCEPROP 1 LASTPIN (-1575 2625) BN 6
J 2
(-1563 2633);
DISPLAY 0.680851 (-1563 2633);
PAINT GREEN (-1563 2633);
FORCEPROP 2 LAST CDS_LIB standard
J 0
(-1625 2625);
DISPLAY INVISIBLE (-1625 2625);
FORCEPROP 1 LAST BODY_TYPE PLUMBING
J 2
(-1625 2675);
DISPLAY 0.872340 (-1625 2675);
PAINT GREEN (-1625 2675);
DISPLAY INVISIBLE (-1625 2675);
FORCEPROP 1 LAST HDL_TAP TRUE
J 2
(-1950 2500);
DISPLAY 0.872340 (-1950 2500);
DISPLAY INVISIBLE (-1950 2500);
FORCEPROP 1 LAST PATH I40
J 2
(-1623 2625);
DISPLAY 0.872340 (-1623 2625);
PAINT GREEN (-1623 2625);
DISPLAY INVISIBLE (-1623 2625);
FORCEADD TAP..1
R 2
(-1625 3475);
FORCEPROP 3 LASTPIN (-1575 3475) SIG_NAME M_A_CPU1_SB_CA<2>
J 0
(-1565 3485);
DISPLAY 0.659574 (-1565 3485);
PAINT MONO (-1565 3485);
DISPLAY INVISIBLE (-1565 3485);
FORCEPROP 1 LASTPIN (-1575 3475) BN 2
J 2
(-1563 3483);
DISPLAY 0.680851 (-1563 3483);
PAINT GREEN (-1563 3483);
FORCEPROP 2 LAST CDS_LIB standard
J 0
(-1625 3475);
DISPLAY INVISIBLE (-1625 3475);
FORCEPROP 1 LAST BODY_TYPE PLUMBING
J 2
(-1625 3525);
DISPLAY 0.872340 (-1625 3525);
PAINT GREEN (-1625 3525);
DISPLAY INVISIBLE (-1625 3525);
FORCEPROP 1 LAST HDL_TAP TRUE
J 2
(-1950 3350);
DISPLAY 0.872340 (-1950 3350);
DISPLAY INVISIBLE (-1950 3350);
FORCEPROP 1 LAST PATH I41
J 2
(-1623 3475);
DISPLAY 0.872340 (-1623 3475);
PAINT GREEN (-1623 3475);
DISPLAY INVISIBLE (-1623 3475);
FORCEADD TAP..1
R 2
(-1625 3425);
FORCEPROP 3 LASTPIN (-1575 3425) SIG_NAME M_A_CPU1_SB_CA<1>
J 0
(-1565 3435);
DISPLAY 0.659574 (-1565 3435);
PAINT MONO (-1565 3435);
DISPLAY INVISIBLE (-1565 3435);
FORCEPROP 1 LASTPIN (-1575 3425) BN 1
J 2
(-1563 3433);
DISPLAY 0.680851 (-1563 3433);
PAINT GREEN (-1563 3433);
FORCEPROP 2 LAST CDS_LIB standard
J 0
(-1625 3425);
DISPLAY INVISIBLE (-1625 3425);
FORCEPROP 1 LAST BODY_TYPE PLUMBING
J 2
(-1625 3475);
DISPLAY 0.872340 (-1625 3475);
PAINT GREEN (-1625 3475);
DISPLAY INVISIBLE (-1625 3475);
FORCEPROP 1 LAST HDL_TAP TRUE
J 2
(-1950 3300);
DISPLAY 0.872340 (-1950 3300);
DISPLAY INVISIBLE (-1950 3300);
FORCEPROP 1 LAST PATH I42
J 2
(-1623 3425);
DISPLAY 0.872340 (-1623 3425);
PAINT GREEN (-1623 3425);
DISPLAY INVISIBLE (-1623 3425);
FORCEADD TAP..1
R 2
(-1625 3375);
FORCEPROP 3 LASTPIN (-1575 3375) SIG_NAME M_A_CPU1_SB_CA<0>
J 0
(-1565 3385);
DISPLAY 0.659574 (-1565 3385);
PAINT MONO (-1565 3385);
DISPLAY INVISIBLE (-1565 3385);
FORCEPROP 1 LASTPIN (-1575 3375) BN 0
J 2
(-1563 3383);
DISPLAY 0.680851 (-1563 3383);
PAINT GREEN (-1563 3383);
FORCEPROP 2 LAST CDS_LIB standard
J 0
(-1625 3375);
DISPLAY INVISIBLE (-1625 3375);
FORCEPROP 1 LAST BODY_TYPE PLUMBING
J 2
(-1625 3425);
DISPLAY 0.872340 (-1625 3425);
PAINT GREEN (-1625 3425);
DISPLAY INVISIBLE (-1625 3425);
FORCEPROP 1 LAST HDL_TAP TRUE
J 2
(-1950 3250);
DISPLAY 0.872340 (-1950 3250);
DISPLAY INVISIBLE (-1950 3250);
FORCEPROP 1 LAST PATH I43
J 2
(-1623 3375);
DISPLAY 0.872340 (-1623 3375);
PAINT GREEN (-1623 3375);
DISPLAY INVISIBLE (-1623 3375);
FORCEADD TAP..1
R 2
(-1625 3575);
FORCEPROP 3 LASTPIN (-1575 3575) SIG_NAME M_A_CPU1_SB_CA<4>
J 0
(-1565 3585);
DISPLAY 0.659574 (-1565 3585);
PAINT MONO (-1565 3585);
DISPLAY INVISIBLE (-1565 3585);
FORCEPROP 1 LASTPIN (-1575 3575) BN 4
J 2
(-1563 3583);
DISPLAY 0.680851 (-1563 3583);
PAINT GREEN (-1563 3583);
FORCEPROP 2 LAST CDS_LIB standard
J 0
(-1625 3575);
DISPLAY INVISIBLE (-1625 3575);
FORCEPROP 1 LAST BODY_TYPE PLUMBING
J 2
(-1625 3625);
DISPLAY 0.872340 (-1625 3625);
PAINT GREEN (-1625 3625);
DISPLAY INVISIBLE (-1625 3625);
FORCEPROP 1 LAST HDL_TAP TRUE
J 2
(-1950 3450);
DISPLAY 0.872340 (-1950 3450);
DISPLAY INVISIBLE (-1950 3450);
FORCEPROP 1 LAST PATH I44
J 2
(-1623 3575);
DISPLAY 0.872340 (-1623 3575);
PAINT GREEN (-1623 3575);
DISPLAY INVISIBLE (-1623 3575);
FORCEADD TAP..1
R 2
(-1625 3525);
FORCEPROP 3 LASTPIN (-1575 3525) SIG_NAME M_A_CPU1_SB_CA<3>
J 0
(-1565 3535);
DISPLAY 0.659574 (-1565 3535);
PAINT MONO (-1565 3535);
DISPLAY INVISIBLE (-1565 3535);
FORCEPROP 1 LASTPIN (-1575 3525) BN 3
J 2
(-1563 3533);
DISPLAY 0.680851 (-1563 3533);
PAINT GREEN (-1563 3533);
FORCEPROP 2 LAST CDS_LIB standard
J 0
(-1625 3525);
DISPLAY INVISIBLE (-1625 3525);
FORCEPROP 1 LAST BODY_TYPE PLUMBING
J 2
(-1625 3575);
DISPLAY 0.872340 (-1625 3575);
PAINT GREEN (-1625 3575);
DISPLAY INVISIBLE (-1625 3575);
FORCEPROP 1 LAST HDL_TAP TRUE
J 2
(-1950 3400);
DISPLAY 0.872340 (-1950 3400);
DISPLAY INVISIBLE (-1950 3400);
FORCEPROP 1 LAST PATH I45
J 2
(-1623 3525);
DISPLAY 0.872340 (-1623 3525);
PAINT GREEN (-1623 3525);
DISPLAY INVISIBLE (-1623 3525);
FORCEADD TAP..1
R 2
(-1625 3675);
FORCEPROP 3 LASTPIN (-1575 3675) SIG_NAME M_A_CPU1_SB_CA<6>
J 0
(-1565 3685);
DISPLAY 0.659574 (-1565 3685);
PAINT MONO (-1565 3685);
DISPLAY INVISIBLE (-1565 3685);
FORCEPROP 1 LASTPIN (-1575 3675) BN 6
J 2
(-1563 3683);
DISPLAY 0.680851 (-1563 3683);
PAINT GREEN (-1563 3683);
FORCEPROP 2 LAST CDS_LIB standard
J 0
(-1625 3675);
DISPLAY INVISIBLE (-1625 3675);
FORCEPROP 1 LAST BODY_TYPE PLUMBING
J 2
(-1625 3725);
DISPLAY 0.872340 (-1625 3725);
PAINT GREEN (-1625 3725);
DISPLAY INVISIBLE (-1625 3725);
FORCEPROP 1 LAST HDL_TAP TRUE
J 2
(-1950 3550);
DISPLAY 0.872340 (-1950 3550);
DISPLAY INVISIBLE (-1950 3550);
FORCEPROP 1 LAST PATH I46
J 2
(-1623 3675);
DISPLAY 0.872340 (-1623 3675);
PAINT GREEN (-1623 3675);
DISPLAY INVISIBLE (-1623 3675);
FORCEADD TAP..1
R 2
(-1625 3625);
FORCEPROP 3 LASTPIN (-1575 3625) SIG_NAME M_A_CPU1_SB_CA<5>
J 0
(-1565 3635);
DISPLAY 0.659574 (-1565 3635);
PAINT MONO (-1565 3635);
DISPLAY INVISIBLE (-1565 3635);
FORCEPROP 1 LASTPIN (-1575 3625) BN 5
J 2
(-1563 3633);
DISPLAY 0.680851 (-1563 3633);
PAINT GREEN (-1563 3633);
FORCEPROP 2 LAST CDS_LIB standard
J 0
(-1625 3625);
DISPLAY INVISIBLE (-1625 3625);
FORCEPROP 1 LAST BODY_TYPE PLUMBING
J 2
(-1625 3675);
DISPLAY 0.872340 (-1625 3675);
PAINT GREEN (-1625 3675);
DISPLAY INVISIBLE (-1625 3675);
FORCEPROP 1 LAST HDL_TAP TRUE
J 2
(-1950 3500);
DISPLAY 0.872340 (-1950 3500);
DISPLAY INVISIBLE (-1950 3500);
FORCEPROP 1 LAST PATH I47
J 2
(-1623 3625);
DISPLAY 0.872340 (-1623 3625);
PAINT GREEN (-1623 3625);
DISPLAY INVISIBLE (-1623 3625);
FORCEADD TAP..1
R 2
(-1625 3825);
FORCEPROP 3 LASTPIN (-1575 3825) SIG_NAME M_A_CPU1_SA_CA<1>
J 0
(-1565 3835);
DISPLAY 0.659574 (-1565 3835);
PAINT MONO (-1565 3835);
DISPLAY INVISIBLE (-1565 3835);
FORCEPROP 1 LASTPIN (-1575 3825) BN 1
J 2
(-1563 3833);
DISPLAY 0.680851 (-1563 3833);
PAINT GREEN (-1563 3833);
FORCEPROP 2 LAST CDS_LIB standard
J 0
(-1625 3825);
DISPLAY INVISIBLE (-1625 3825);
FORCEPROP 1 LAST BODY_TYPE PLUMBING
J 2
(-1625 3875);
DISPLAY 0.872340 (-1625 3875);
PAINT GREEN (-1625 3875);
DISPLAY INVISIBLE (-1625 3875);
FORCEPROP 1 LAST HDL_TAP TRUE
J 2
(-1950 3700);
DISPLAY 0.872340 (-1950 3700);
DISPLAY INVISIBLE (-1950 3700);
FORCEPROP 1 LAST PATH I48
J 2
(-1623 3825);
DISPLAY 0.872340 (-1623 3825);
PAINT GREEN (-1623 3825);
DISPLAY INVISIBLE (-1623 3825);
FORCEADD TAP..1
R 2
(-1625 3775);
FORCEPROP 3 LASTPIN (-1575 3775) SIG_NAME M_A_CPU1_SA_CA<0>
J 0
(-1565 3785);
DISPLAY 0.659574 (-1565 3785);
PAINT MONO (-1565 3785);
DISPLAY INVISIBLE (-1565 3785);
FORCEPROP 1 LASTPIN (-1575 3775) BN 0
J 2
(-1563 3783);
DISPLAY 0.680851 (-1563 3783);
PAINT GREEN (-1563 3783);
FORCEPROP 2 LAST CDS_LIB standard
J 0
(-1625 3775);
DISPLAY INVISIBLE (-1625 3775);
FORCEPROP 1 LAST BODY_TYPE PLUMBING
J 2
(-1625 3825);
DISPLAY 0.872340 (-1625 3825);
PAINT GREEN (-1625 3825);
DISPLAY INVISIBLE (-1625 3825);
FORCEPROP 1 LAST HDL_TAP TRUE
J 2
(-1950 3650);
DISPLAY 0.872340 (-1950 3650);
DISPLAY INVISIBLE (-1950 3650);
FORCEPROP 1 LAST PATH I49
J 2
(-1623 3775);
DISPLAY 0.872340 (-1623 3775);
PAINT GREEN (-1623 3775);
DISPLAY INVISIBLE (-1623 3775);
FORCEADD OFFPAGE..3
R 2
(-2550 1225);
FORCEPROP 2 LAST $XR0 114 
J 0
(-2830 1225);
DISPLAY 0.638298 (-2830 1225);
PAINT MONO (-2830 1225);
FORCEPROP 2 LAST CDS_LIB standard
J 0
(-2550 1225);
PAINT MONO (-2550 1225);
DISPLAY INVISIBLE (-2550 1225);
FORCEPROP 1 LAST OFFPAGE TRUE
J 2
(-2875 1100);
DISPLAY 0.872340 (-2875 1100);
DISPLAY INVISIBLE (-2875 1100);
FORCEPROP 1 LAST COMMENT_BODY TRUE
J 2
(-2500 1125);
DISPLAY 0.872340 (-2500 1125);
PAINT GREEN (-2500 1125);
DISPLAY INVISIBLE (-2500 1125);
FORCEPROP 2 LAST PATH I5
J 0
(-2500 1300);
DISPLAY 1.021277 (-2500 1300);
DISPLAY INVISIBLE (-2500 1300);
FORCEADD TAP..1
(25 875);
FORCEPROP 3 LASTPIN (-25 875) SIG_NAME M_A_CPU1_SB_DQ<0>
J 0
(-15 885);
DISPLAY 0.659574 (-15 885);
PAINT MONO (-15 885);
DISPLAY INVISIBLE (-15 885);
FORCEPROP 1 LASTPIN (-25 875) BN 0
J 0
(-37 883);
DISPLAY 0.680851 (-37 883);
PAINT GREEN (-37 883);
FORCEPROP 2 LAST CDS_LIB standard
J 0
(25 875);
PAINT MONO (25 875);
DISPLAY INVISIBLE (25 875);
FORCEPROP 1 LAST BODY_TYPE PLUMBING
J 0
(25 925);
DISPLAY 0.872340 (25 925);
PAINT GREEN (25 925);
DISPLAY INVISIBLE (25 925);
FORCEPROP 1 LAST HDL_TAP TRUE
J 0
(350 750);
DISPLAY 0.872340 (350 750);
DISPLAY INVISIBLE (350 750);
FORCEPROP 1 LAST PATH I50
J 0
(23 875);
DISPLAY 0.872340 (23 875);
PAINT GREEN (23 875);
DISPLAY INVISIBLE (23 875);
FORCEADD TAP..1
(25 925);
FORCEPROP 3 LASTPIN (-25 925) SIG_NAME M_A_CPU1_SB_DQ<1>
J 0
(-15 935);
DISPLAY 0.659574 (-15 935);
PAINT MONO (-15 935);
DISPLAY INVISIBLE (-15 935);
FORCEPROP 1 LASTPIN (-25 925) BN 1
J 0
(-37 933);
DISPLAY 0.680851 (-37 933);
PAINT GREEN (-37 933);
FORCEPROP 2 LAST CDS_LIB standard
J 0
(25 925);
PAINT MONO (25 925);
DISPLAY INVISIBLE (25 925);
FORCEPROP 1 LAST BODY_TYPE PLUMBING
J 0
(25 975);
DISPLAY 0.872340 (25 975);
PAINT GREEN (25 975);
DISPLAY INVISIBLE (25 975);
FORCEPROP 1 LAST HDL_TAP TRUE
J 0
(350 800);
DISPLAY 0.872340 (350 800);
DISPLAY INVISIBLE (350 800);
FORCEPROP 1 LAST PATH I51
J 0
(23 925);
DISPLAY 0.872340 (23 925);
PAINT GREEN (23 925);
DISPLAY INVISIBLE (23 925);
FORCEADD TAP..1
(25 1025);
FORCEPROP 3 LASTPIN (-25 1025) SIG_NAME M_A_CPU1_SB_DQ<3>
J 0
(-15 1035);
DISPLAY 0.659574 (-15 1035);
PAINT MONO (-15 1035);
DISPLAY INVISIBLE (-15 1035);
FORCEPROP 1 LASTPIN (-25 1025) BN 3
J 0
(-37 1033);
DISPLAY 0.680851 (-37 1033);
PAINT GREEN (-37 1033);
FORCEPROP 2 LAST CDS_LIB standard
J 0
(25 1025);
PAINT MONO (25 1025);
DISPLAY INVISIBLE (25 1025);
FORCEPROP 1 LAST BODY_TYPE PLUMBING
J 0
(25 1075);
DISPLAY 0.872340 (25 1075);
PAINT GREEN (25 1075);
DISPLAY INVISIBLE (25 1075);
FORCEPROP 1 LAST HDL_TAP TRUE
J 0
(350 900);
DISPLAY 0.872340 (350 900);
DISPLAY INVISIBLE (350 900);
FORCEPROP 1 LAST PATH I52
J 0
(23 1025);
DISPLAY 0.872340 (23 1025);
PAINT GREEN (23 1025);
DISPLAY INVISIBLE (23 1025);
FORCEADD TAP..1
(25 975);
FORCEPROP 3 LASTPIN (-25 975) SIG_NAME M_A_CPU1_SB_DQ<2>
J 0
(-15 985);
DISPLAY 0.659574 (-15 985);
PAINT MONO (-15 985);
DISPLAY INVISIBLE (-15 985);
FORCEPROP 1 LASTPIN (-25 975) BN 2
J 0
(-37 983);
DISPLAY 0.680851 (-37 983);
PAINT GREEN (-37 983);
FORCEPROP 2 LAST CDS_LIB standard
J 0
(25 975);
PAINT MONO (25 975);
DISPLAY INVISIBLE (25 975);
FORCEPROP 1 LAST BODY_TYPE PLUMBING
J 0
(25 1025);
DISPLAY 0.872340 (25 1025);
PAINT GREEN (25 1025);
DISPLAY INVISIBLE (25 1025);
FORCEPROP 1 LAST HDL_TAP TRUE
J 0
(350 850);
DISPLAY 0.872340 (350 850);
DISPLAY INVISIBLE (350 850);
FORCEPROP 1 LAST PATH I53
J 0
(23 975);
DISPLAY 0.872340 (23 975);
PAINT GREEN (23 975);
DISPLAY INVISIBLE (23 975);
FORCEADD TAP..1
(25 1175);
FORCEPROP 3 LASTPIN (-25 1175) SIG_NAME M_A_CPU1_SB_DQ<6>
J 0
(-15 1185);
DISPLAY 0.659574 (-15 1185);
PAINT MONO (-15 1185);
DISPLAY INVISIBLE (-15 1185);
FORCEPROP 1 LASTPIN (-25 1175) BN 6
J 0
(-37 1183);
DISPLAY 0.680851 (-37 1183);
PAINT GREEN (-37 1183);
FORCEPROP 2 LAST CDS_LIB standard
J 0
(25 1175);
PAINT MONO (25 1175);
DISPLAY INVISIBLE (25 1175);
FORCEPROP 1 LAST BODY_TYPE PLUMBING
J 0
(25 1225);
DISPLAY 0.872340 (25 1225);
PAINT GREEN (25 1225);
DISPLAY INVISIBLE (25 1225);
FORCEPROP 1 LAST HDL_TAP TRUE
J 0
(350 1050);
DISPLAY 0.872340 (350 1050);
DISPLAY INVISIBLE (350 1050);
FORCEPROP 1 LAST PATH I54
J 0
(23 1175);
DISPLAY 0.872340 (23 1175);
PAINT GREEN (23 1175);
DISPLAY INVISIBLE (23 1175);
FORCEADD TAP..1
(25 1125);
FORCEPROP 3 LASTPIN (-25 1125) SIG_NAME M_A_CPU1_SB_DQ<5>
J 0
(-15 1135);
DISPLAY 0.659574 (-15 1135);
PAINT MONO (-15 1135);
DISPLAY INVISIBLE (-15 1135);
FORCEPROP 1 LASTPIN (-25 1125) BN 5
J 0
(-37 1133);
DISPLAY 0.680851 (-37 1133);
PAINT GREEN (-37 1133);
FORCEPROP 2 LAST CDS_LIB standard
J 0
(25 1125);
PAINT MONO (25 1125);
DISPLAY INVISIBLE (25 1125);
FORCEPROP 1 LAST BODY_TYPE PLUMBING
J 0
(25 1175);
DISPLAY 0.872340 (25 1175);
PAINT GREEN (25 1175);
DISPLAY INVISIBLE (25 1175);
FORCEPROP 1 LAST HDL_TAP TRUE
J 0
(350 1000);
DISPLAY 0.872340 (350 1000);
DISPLAY INVISIBLE (350 1000);
FORCEPROP 1 LAST PATH I55
J 0
(23 1125);
DISPLAY 0.872340 (23 1125);
PAINT GREEN (23 1125);
DISPLAY INVISIBLE (23 1125);
FORCEADD TAP..1
(25 1075);
FORCEPROP 3 LASTPIN (-25 1075) SIG_NAME M_A_CPU1_SB_DQ<4>
J 0
(-15 1085);
DISPLAY 0.659574 (-15 1085);
PAINT MONO (-15 1085);
DISPLAY INVISIBLE (-15 1085);
FORCEPROP 1 LASTPIN (-25 1075) BN 4
J 0
(-37 1083);
DISPLAY 0.680851 (-37 1083);
PAINT GREEN (-37 1083);
FORCEPROP 2 LAST CDS_LIB standard
J 0
(25 1075);
PAINT MONO (25 1075);
DISPLAY INVISIBLE (25 1075);
FORCEPROP 1 LAST BODY_TYPE PLUMBING
J 0
(25 1125);
DISPLAY 0.872340 (25 1125);
PAINT GREEN (25 1125);
DISPLAY INVISIBLE (25 1125);
FORCEPROP 1 LAST HDL_TAP TRUE
J 0
(350 950);
DISPLAY 0.872340 (350 950);
DISPLAY INVISIBLE (350 950);
FORCEPROP 1 LAST PATH I56
J 0
(23 1075);
DISPLAY 0.872340 (23 1075);
PAINT GREEN (23 1075);
DISPLAY INVISIBLE (23 1075);
FORCEADD TAP..1
(25 1225);
FORCEPROP 3 LASTPIN (-25 1225) SIG_NAME M_A_CPU1_SB_DQ<7>
J 0
(-15 1235);
DISPLAY 0.659574 (-15 1235);
PAINT MONO (-15 1235);
DISPLAY INVISIBLE (-15 1235);
FORCEPROP 1 LASTPIN (-25 1225) BN 7
J 0
(-37 1233);
DISPLAY 0.680851 (-37 1233);
PAINT GREEN (-37 1233);
FORCEPROP 2 LAST CDS_LIB standard
J 0
(25 1225);
PAINT MONO (25 1225);
DISPLAY INVISIBLE (25 1225);
FORCEPROP 1 LAST BODY_TYPE PLUMBING
J 0
(25 1275);
DISPLAY 0.872340 (25 1275);
PAINT GREEN (25 1275);
DISPLAY INVISIBLE (25 1275);
FORCEPROP 1 LAST HDL_TAP TRUE
J 0
(350 1100);
DISPLAY 0.872340 (350 1100);
DISPLAY INVISIBLE (350 1100);
FORCEPROP 1 LAST PATH I57
J 0
(23 1225);
DISPLAY 0.872340 (23 1225);
PAINT GREEN (23 1225);
DISPLAY INVISIBLE (23 1225);
FORCEADD TAP..1
(25 1275);
FORCEPROP 3 LASTPIN (-25 1275) SIG_NAME M_A_CPU1_SB_DQ<8>
J 0
(-15 1285);
DISPLAY 0.659574 (-15 1285);
PAINT MONO (-15 1285);
DISPLAY INVISIBLE (-15 1285);
FORCEPROP 1 LASTPIN (-25 1275) BN 8
J 0
(-37 1283);
DISPLAY 0.680851 (-37 1283);
PAINT GREEN (-37 1283);
FORCEPROP 2 LAST CDS_LIB standard
J 0
(25 1275);
PAINT MONO (25 1275);
DISPLAY INVISIBLE (25 1275);
FORCEPROP 1 LAST BODY_TYPE PLUMBING
J 0
(25 1325);
DISPLAY 0.872340 (25 1325);
PAINT GREEN (25 1325);
DISPLAY INVISIBLE (25 1325);
FORCEPROP 1 LAST HDL_TAP TRUE
J 0
(350 1150);
DISPLAY 0.872340 (350 1150);
DISPLAY INVISIBLE (350 1150);
FORCEPROP 1 LAST PATH I58
J 0
(23 1275);
DISPLAY 0.872340 (23 1275);
PAINT GREEN (23 1275);
DISPLAY INVISIBLE (23 1275);
FORCEADD TAP..1
(25 1325);
FORCEPROP 3 LASTPIN (-25 1325) SIG_NAME M_A_CPU1_SB_DQ<9>
J 0
(-15 1335);
DISPLAY 0.659574 (-15 1335);
PAINT MONO (-15 1335);
DISPLAY INVISIBLE (-15 1335);
FORCEPROP 1 LASTPIN (-25 1325) BN 9
J 0
(-37 1333);
DISPLAY 0.680851 (-37 1333);
PAINT GREEN (-37 1333);
FORCEPROP 2 LAST CDS_LIB standard
J 0
(25 1325);
PAINT MONO (25 1325);
DISPLAY INVISIBLE (25 1325);
FORCEPROP 1 LAST BODY_TYPE PLUMBING
J 0
(25 1375);
DISPLAY 0.872340 (25 1375);
PAINT GREEN (25 1375);
DISPLAY INVISIBLE (25 1375);
FORCEPROP 1 LAST HDL_TAP TRUE
J 0
(350 1200);
DISPLAY 0.872340 (350 1200);
DISPLAY INVISIBLE (350 1200);
FORCEPROP 1 LAST PATH I59
J 0
(23 1325);
DISPLAY 0.872340 (23 1325);
PAINT GREEN (23 1325);
DISPLAY INVISIBLE (23 1325);
FORCEADD TAP..1
(25 1375);
FORCEPROP 3 LASTPIN (-25 1375) SIG_NAME M_A_CPU1_SB_DQ<10>
J 0
(-15 1385);
DISPLAY 0.659574 (-15 1385);
PAINT MONO (-15 1385);
DISPLAY INVISIBLE (-15 1385);
FORCEPROP 1 LASTPIN (-25 1375) BN 10
J 0
(-37 1383);
DISPLAY 0.680851 (-37 1383);
PAINT GREEN (-37 1383);
FORCEPROP 2 LAST CDS_LIB standard
J 0
(25 1375);
PAINT MONO (25 1375);
DISPLAY INVISIBLE (25 1375);
FORCEPROP 1 LAST BODY_TYPE PLUMBING
J 0
(25 1425);
DISPLAY 0.872340 (25 1425);
PAINT GREEN (25 1425);
DISPLAY INVISIBLE (25 1425);
FORCEPROP 1 LAST HDL_TAP TRUE
J 0
(350 1250);
DISPLAY 0.872340 (350 1250);
DISPLAY INVISIBLE (350 1250);
FORCEPROP 1 LAST PATH I60
J 0
(23 1375);
DISPLAY 0.872340 (23 1375);
PAINT GREEN (23 1375);
DISPLAY INVISIBLE (23 1375);
FORCEADD TAP..1
(25 1425);
FORCEPROP 3 LASTPIN (-25 1425) SIG_NAME M_A_CPU1_SB_DQ<11>
J 0
(-15 1435);
DISPLAY 0.659574 (-15 1435);
PAINT MONO (-15 1435);
DISPLAY INVISIBLE (-15 1435);
FORCEPROP 1 LASTPIN (-25 1425) BN 11
J 0
(-37 1433);
DISPLAY 0.680851 (-37 1433);
PAINT GREEN (-37 1433);
FORCEPROP 2 LAST CDS_LIB standard
J 0
(25 1425);
PAINT MONO (25 1425);
DISPLAY INVISIBLE (25 1425);
FORCEPROP 1 LAST BODY_TYPE PLUMBING
J 0
(25 1475);
DISPLAY 0.872340 (25 1475);
PAINT GREEN (25 1475);
DISPLAY INVISIBLE (25 1475);
FORCEPROP 1 LAST HDL_TAP TRUE
J 0
(350 1300);
DISPLAY 0.872340 (350 1300);
DISPLAY INVISIBLE (350 1300);
FORCEPROP 1 LAST PATH I61
J 0
(23 1425);
DISPLAY 0.872340 (23 1425);
PAINT GREEN (23 1425);
DISPLAY INVISIBLE (23 1425);
FORCEADD TAP..1
(25 1475);
FORCEPROP 3 LASTPIN (-25 1475) SIG_NAME M_A_CPU1_SB_DQ<12>
J 0
(-15 1485);
DISPLAY 0.659574 (-15 1485);
PAINT MONO (-15 1485);
DISPLAY INVISIBLE (-15 1485);
FORCEPROP 1 LASTPIN (-25 1475) BN 12
J 0
(-37 1483);
DISPLAY 0.680851 (-37 1483);
PAINT GREEN (-37 1483);
FORCEPROP 2 LAST CDS_LIB standard
J 0
(25 1475);
PAINT MONO (25 1475);
DISPLAY INVISIBLE (25 1475);
FORCEPROP 1 LAST BODY_TYPE PLUMBING
J 0
(25 1525);
DISPLAY 0.872340 (25 1525);
PAINT GREEN (25 1525);
DISPLAY INVISIBLE (25 1525);
FORCEPROP 1 LAST HDL_TAP TRUE
J 0
(350 1350);
DISPLAY 0.872340 (350 1350);
DISPLAY INVISIBLE (350 1350);
FORCEPROP 1 LAST PATH I62
J 0
(23 1475);
DISPLAY 0.872340 (23 1475);
PAINT GREEN (23 1475);
DISPLAY INVISIBLE (23 1475);
FORCEADD TAP..1
(25 1525);
FORCEPROP 3 LASTPIN (-25 1525) SIG_NAME M_A_CPU1_SB_DQ<13>
J 0
(-15 1535);
DISPLAY 0.659574 (-15 1535);
PAINT MONO (-15 1535);
DISPLAY INVISIBLE (-15 1535);
FORCEPROP 1 LASTPIN (-25 1525) BN 13
J 0
(-37 1533);
DISPLAY 0.680851 (-37 1533);
PAINT GREEN (-37 1533);
FORCEPROP 2 LAST CDS_LIB standard
J 0
(25 1525);
PAINT MONO (25 1525);
DISPLAY INVISIBLE (25 1525);
FORCEPROP 1 LAST BODY_TYPE PLUMBING
J 0
(25 1575);
DISPLAY 0.872340 (25 1575);
PAINT GREEN (25 1575);
DISPLAY INVISIBLE (25 1575);
FORCEPROP 1 LAST HDL_TAP TRUE
J 0
(350 1400);
DISPLAY 0.872340 (350 1400);
DISPLAY INVISIBLE (350 1400);
FORCEPROP 1 LAST PATH I63
J 0
(23 1525);
DISPLAY 0.872340 (23 1525);
PAINT GREEN (23 1525);
DISPLAY INVISIBLE (23 1525);
FORCEADD TAP..1
(25 1575);
FORCEPROP 3 LASTPIN (-25 1575) SIG_NAME M_A_CPU1_SB_DQ<14>
J 0
(-15 1585);
DISPLAY 0.659574 (-15 1585);
PAINT MONO (-15 1585);
DISPLAY INVISIBLE (-15 1585);
FORCEPROP 1 LASTPIN (-25 1575) BN 14
J 0
(-37 1583);
DISPLAY 0.680851 (-37 1583);
PAINT GREEN (-37 1583);
FORCEPROP 2 LAST CDS_LIB standard
J 0
(25 1575);
PAINT MONO (25 1575);
DISPLAY INVISIBLE (25 1575);
FORCEPROP 1 LAST BODY_TYPE PLUMBING
J 0
(25 1625);
DISPLAY 0.872340 (25 1625);
PAINT GREEN (25 1625);
DISPLAY INVISIBLE (25 1625);
FORCEPROP 1 LAST HDL_TAP TRUE
J 0
(350 1450);
DISPLAY 0.872340 (350 1450);
DISPLAY INVISIBLE (350 1450);
FORCEPROP 1 LAST PATH I64
J 0
(23 1575);
DISPLAY 0.872340 (23 1575);
PAINT GREEN (23 1575);
DISPLAY INVISIBLE (23 1575);
FORCEADD TAP..1
(25 1625);
FORCEPROP 3 LASTPIN (-25 1625) SIG_NAME M_A_CPU1_SB_DQ<15>
J 0
(-15 1635);
DISPLAY 0.659574 (-15 1635);
PAINT MONO (-15 1635);
DISPLAY INVISIBLE (-15 1635);
FORCEPROP 1 LASTPIN (-25 1625) BN 15
J 0
(-37 1633);
DISPLAY 0.680851 (-37 1633);
PAINT GREEN (-37 1633);
FORCEPROP 2 LAST CDS_LIB standard
J 0
(25 1625);
PAINT MONO (25 1625);
DISPLAY INVISIBLE (25 1625);
FORCEPROP 1 LAST BODY_TYPE PLUMBING
J 0
(25 1675);
DISPLAY 0.872340 (25 1675);
PAINT GREEN (25 1675);
DISPLAY INVISIBLE (25 1675);
FORCEPROP 1 LAST HDL_TAP TRUE
J 0
(350 1500);
DISPLAY 0.872340 (350 1500);
DISPLAY INVISIBLE (350 1500);
FORCEPROP 1 LAST PATH I65
J 0
(23 1625);
DISPLAY 0.872340 (23 1625);
PAINT GREEN (23 1625);
DISPLAY INVISIBLE (23 1625);
FORCEADD TAP..1
(25 1675);
FORCEPROP 3 LASTPIN (-25 1675) SIG_NAME M_A_CPU1_SB_DQ<16>
J 0
(-15 1685);
DISPLAY 0.659574 (-15 1685);
PAINT MONO (-15 1685);
DISPLAY INVISIBLE (-15 1685);
FORCEPROP 1 LASTPIN (-25 1675) BN 16
J 0
(-37 1683);
DISPLAY 0.680851 (-37 1683);
PAINT GREEN (-37 1683);
FORCEPROP 2 LAST CDS_LIB standard
J 0
(25 1675);
PAINT MONO (25 1675);
DISPLAY INVISIBLE (25 1675);
FORCEPROP 1 LAST BODY_TYPE PLUMBING
J 0
(25 1725);
DISPLAY 0.872340 (25 1725);
PAINT GREEN (25 1725);
DISPLAY INVISIBLE (25 1725);
FORCEPROP 1 LAST HDL_TAP TRUE
J 0
(350 1550);
DISPLAY 0.872340 (350 1550);
DISPLAY INVISIBLE (350 1550);
FORCEPROP 1 LAST PATH I66
J 0
(23 1675);
DISPLAY 0.872340 (23 1675);
PAINT GREEN (23 1675);
DISPLAY INVISIBLE (23 1675);
FORCEADD TAP..1
(25 1725);
FORCEPROP 3 LASTPIN (-25 1725) SIG_NAME M_A_CPU1_SB_DQ<17>
J 0
(-15 1735);
DISPLAY 0.659574 (-15 1735);
PAINT MONO (-15 1735);
DISPLAY INVISIBLE (-15 1735);
FORCEPROP 1 LASTPIN (-25 1725) BN 17
J 0
(-37 1733);
DISPLAY 0.680851 (-37 1733);
PAINT GREEN (-37 1733);
FORCEPROP 2 LAST CDS_LIB standard
J 0
(25 1725);
PAINT MONO (25 1725);
DISPLAY INVISIBLE (25 1725);
FORCEPROP 1 LAST BODY_TYPE PLUMBING
J 0
(25 1775);
DISPLAY 0.872340 (25 1775);
PAINT GREEN (25 1775);
DISPLAY INVISIBLE (25 1775);
FORCEPROP 1 LAST HDL_TAP TRUE
J 0
(350 1600);
DISPLAY 0.872340 (350 1600);
DISPLAY INVISIBLE (350 1600);
FORCEPROP 1 LAST PATH I67
J 0
(23 1725);
DISPLAY 0.872340 (23 1725);
PAINT GREEN (23 1725);
DISPLAY INVISIBLE (23 1725);
FORCEADD TAP..1
(25 1775);
FORCEPROP 3 LASTPIN (-25 1775) SIG_NAME M_A_CPU1_SB_DQ<18>
J 0
(-15 1785);
DISPLAY 0.659574 (-15 1785);
PAINT MONO (-15 1785);
DISPLAY INVISIBLE (-15 1785);
FORCEPROP 1 LASTPIN (-25 1775) BN 18
J 0
(-37 1783);
DISPLAY 0.680851 (-37 1783);
PAINT GREEN (-37 1783);
FORCEPROP 2 LAST CDS_LIB standard
J 0
(25 1775);
PAINT MONO (25 1775);
DISPLAY INVISIBLE (25 1775);
FORCEPROP 1 LAST BODY_TYPE PLUMBING
J 0
(25 1825);
DISPLAY 0.872340 (25 1825);
PAINT GREEN (25 1825);
DISPLAY INVISIBLE (25 1825);
FORCEPROP 1 LAST HDL_TAP TRUE
J 0
(350 1650);
DISPLAY 0.872340 (350 1650);
DISPLAY INVISIBLE (350 1650);
FORCEPROP 1 LAST PATH I68
J 0
(23 1775);
DISPLAY 0.872340 (23 1775);
PAINT GREEN (23 1775);
DISPLAY INVISIBLE (23 1775);
FORCEADD TAP..1
(25 1825);
FORCEPROP 3 LASTPIN (-25 1825) SIG_NAME M_A_CPU1_SB_DQ<19>
J 0
(-15 1835);
DISPLAY 0.659574 (-15 1835);
PAINT MONO (-15 1835);
DISPLAY INVISIBLE (-15 1835);
FORCEPROP 1 LASTPIN (-25 1825) BN 19
J 0
(-37 1833);
DISPLAY 0.680851 (-37 1833);
PAINT GREEN (-37 1833);
FORCEPROP 2 LAST CDS_LIB standard
J 0
(25 1825);
PAINT MONO (25 1825);
DISPLAY INVISIBLE (25 1825);
FORCEPROP 1 LAST BODY_TYPE PLUMBING
J 0
(25 1875);
DISPLAY 0.872340 (25 1875);
PAINT GREEN (25 1875);
DISPLAY INVISIBLE (25 1875);
FORCEPROP 1 LAST HDL_TAP TRUE
J 0
(350 1700);
DISPLAY 0.872340 (350 1700);
DISPLAY INVISIBLE (350 1700);
FORCEPROP 1 LAST PATH I69
J 0
(23 1825);
DISPLAY 0.872340 (23 1825);
PAINT GREEN (23 1825);
DISPLAY INVISIBLE (23 1825);
FORCEADD OFFPAGE..1
(-2450 1525);
FORCEPROP 2 LAST $XR7 105 
J 0
(-2822 1561);
DISPLAY 0.638298 (-2822 1561);
PAINT MONO (-2822 1561);
FORCEPROP 2 LAST $XR6 104 
J 0
(-2702 1561);
DISPLAY 0.638298 (-2702 1561);
PAINT MONO (-2702 1561);
FORCEPROP 2 LAST $XR5 103 
J 0
(-2942 1489);
DISPLAY 0.638298 (-2942 1489);
PAINT MONO (-2942 1489);
FORCEPROP 2 LAST $XR4 102 
J 0
(-2822 1489);
DISPLAY 0.638298 (-2822 1489);
PAINT MONO (-2822 1489);
FORCEPROP 2 LAST $XR3 101 
J 0
(-2702 1489);
DISPLAY 0.638298 (-2702 1489);
PAINT MONO (-2702 1489);
FORCEPROP 2 LAST $XR2 100 
J 0
(-2912 1525);
DISPLAY 0.638298 (-2912 1525);
PAINT MONO (-2912 1525);
FORCEPROP 2 LAST $XR1 99 
J 0
(-2792 1525);
DISPLAY 0.638298 (-2792 1525);
PAINT MONO (-2792 1525);
FORCEPROP 2 LAST $XR0 230 
J 0
(-2702 1525);
DISPLAY 0.638298 (-2702 1525);
PAINT MONO (-2702 1525);
FORCEPROP 2 LAST CDS_LIB standard
J 0
(-2450 1525);
PAINT MONO (-2450 1525);
DISPLAY INVISIBLE (-2450 1525);
FORCEPROP 1 LAST OFFPAGE TRUE
J 0
(-2125 1400);
DISPLAY 0.872340 (-2125 1400);
DISPLAY INVISIBLE (-2125 1400);
FORCEPROP 1 LAST COMMENT_BODY TRUE
J 0
(-2325 1425);
DISPLAY 0.872340 (-2325 1425);
PAINT GREEN (-2325 1425);
DISPLAY INVISIBLE (-2325 1425);
FORCEPROP 2 LAST PATH I7
J 0
(-2400 1600);
DISPLAY 1.021277 (-2400 1600);
DISPLAY INVISIBLE (-2400 1600);
FORCEADD TAP..1
(25 1925);
FORCEPROP 3 LASTPIN (-25 1925) SIG_NAME M_A_CPU1_SB_DQ<21>
J 0
(-15 1935);
DISPLAY 0.659574 (-15 1935);
PAINT MONO (-15 1935);
DISPLAY INVISIBLE (-15 1935);
FORCEPROP 1 LASTPIN (-25 1925) BN 21
J 0
(-37 1933);
DISPLAY 0.680851 (-37 1933);
PAINT GREEN (-37 1933);
FORCEPROP 2 LAST CDS_LIB standard
J 0
(25 1925);
PAINT MONO (25 1925);
DISPLAY INVISIBLE (25 1925);
FORCEPROP 1 LAST BODY_TYPE PLUMBING
J 0
(25 1975);
DISPLAY 0.872340 (25 1975);
PAINT GREEN (25 1975);
DISPLAY INVISIBLE (25 1975);
FORCEPROP 1 LAST HDL_TAP TRUE
J 0
(350 1800);
DISPLAY 0.872340 (350 1800);
DISPLAY INVISIBLE (350 1800);
FORCEPROP 1 LAST PATH I70
J 0
(23 1925);
DISPLAY 0.872340 (23 1925);
PAINT GREEN (23 1925);
DISPLAY INVISIBLE (23 1925);
FORCEADD TAP..1
(25 1875);
FORCEPROP 3 LASTPIN (-25 1875) SIG_NAME M_A_CPU1_SB_DQ<20>
J 0
(-15 1885);
DISPLAY 0.659574 (-15 1885);
PAINT MONO (-15 1885);
DISPLAY INVISIBLE (-15 1885);
FORCEPROP 1 LASTPIN (-25 1875) BN 20
J 0
(-37 1883);
DISPLAY 0.680851 (-37 1883);
PAINT GREEN (-37 1883);
FORCEPROP 2 LAST CDS_LIB standard
J 0
(25 1875);
PAINT MONO (25 1875);
DISPLAY INVISIBLE (25 1875);
FORCEPROP 1 LAST BODY_TYPE PLUMBING
J 0
(25 1925);
DISPLAY 0.872340 (25 1925);
PAINT GREEN (25 1925);
DISPLAY INVISIBLE (25 1925);
FORCEPROP 1 LAST HDL_TAP TRUE
J 0
(350 1750);
DISPLAY 0.872340 (350 1750);
DISPLAY INVISIBLE (350 1750);
FORCEPROP 1 LAST PATH I71
J 0
(23 1875);
DISPLAY 0.872340 (23 1875);
PAINT GREEN (23 1875);
DISPLAY INVISIBLE (23 1875);
FORCEADD TAP..1
(25 2025);
FORCEPROP 3 LASTPIN (-25 2025) SIG_NAME M_A_CPU1_SB_DQ<23>
J 0
(-15 2035);
DISPLAY 0.659574 (-15 2035);
PAINT MONO (-15 2035);
DISPLAY INVISIBLE (-15 2035);
FORCEPROP 1 LASTPIN (-25 2025) BN 23
J 0
(-37 2033);
DISPLAY 0.680851 (-37 2033);
PAINT GREEN (-37 2033);
FORCEPROP 2 LAST CDS_LIB standard
J 0
(25 2025);
DISPLAY INVISIBLE (25 2025);
FORCEPROP 1 LAST BODY_TYPE PLUMBING
J 0
(25 2075);
DISPLAY 0.872340 (25 2075);
PAINT GREEN (25 2075);
DISPLAY INVISIBLE (25 2075);
FORCEPROP 1 LAST HDL_TAP TRUE
J 0
(350 1900);
DISPLAY 0.872340 (350 1900);
DISPLAY INVISIBLE (350 1900);
FORCEPROP 1 LAST PATH I72
J 0
(23 2025);
DISPLAY 0.872340 (23 2025);
PAINT GREEN (23 2025);
DISPLAY INVISIBLE (23 2025);
FORCEADD TAP..1
(25 2075);
FORCEPROP 3 LASTPIN (-25 2075) SIG_NAME M_A_CPU1_SB_DQ<24>
J 0
(-15 2085);
DISPLAY 0.659574 (-15 2085);
PAINT MONO (-15 2085);
DISPLAY INVISIBLE (-15 2085);
FORCEPROP 1 LASTPIN (-25 2075) BN 24
J 0
(-37 2083);
DISPLAY 0.680851 (-37 2083);
PAINT GREEN (-37 2083);
FORCEPROP 2 LAST CDS_LIB standard
J 0
(25 2075);
DISPLAY INVISIBLE (25 2075);
FORCEPROP 1 LAST BODY_TYPE PLUMBING
J 0
(25 2125);
DISPLAY 0.872340 (25 2125);
PAINT GREEN (25 2125);
DISPLAY INVISIBLE (25 2125);
FORCEPROP 1 LAST HDL_TAP TRUE
J 0
(350 1950);
DISPLAY 0.872340 (350 1950);
DISPLAY INVISIBLE (350 1950);
FORCEPROP 1 LAST PATH I73
J 0
(23 2075);
DISPLAY 0.872340 (23 2075);
PAINT GREEN (23 2075);
DISPLAY INVISIBLE (23 2075);
FORCEADD TAP..1
(25 1975);
FORCEPROP 3 LASTPIN (-25 1975) SIG_NAME M_A_CPU1_SB_DQ<22>
J 0
(-15 1985);
DISPLAY 0.659574 (-15 1985);
PAINT MONO (-15 1985);
DISPLAY INVISIBLE (-15 1985);
FORCEPROP 1 LASTPIN (-25 1975) BN 22
J 0
(-37 1983);
DISPLAY 0.680851 (-37 1983);
PAINT GREEN (-37 1983);
FORCEPROP 2 LAST CDS_LIB standard
J 0
(25 1975);
DISPLAY INVISIBLE (25 1975);
FORCEPROP 1 LAST BODY_TYPE PLUMBING
J 0
(25 2025);
DISPLAY 0.872340 (25 2025);
PAINT GREEN (25 2025);
DISPLAY INVISIBLE (25 2025);
FORCEPROP 1 LAST HDL_TAP TRUE
J 0
(350 1850);
DISPLAY 0.872340 (350 1850);
DISPLAY INVISIBLE (350 1850);
FORCEPROP 1 LAST PATH I74
J 0
(23 1975);
DISPLAY 0.872340 (23 1975);
PAINT GREEN (23 1975);
DISPLAY INVISIBLE (23 1975);
FORCEADD TAP..1
(25 2125);
FORCEPROP 3 LASTPIN (-25 2125) SIG_NAME M_A_CPU1_SB_DQ<25>
J 0
(-15 2135);
DISPLAY 0.659574 (-15 2135);
PAINT MONO (-15 2135);
DISPLAY INVISIBLE (-15 2135);
FORCEPROP 1 LASTPIN (-25 2125) BN 25
J 0
(-37 2133);
DISPLAY 0.680851 (-37 2133);
PAINT GREEN (-37 2133);
FORCEPROP 2 LAST CDS_LIB standard
J 0
(25 2125);
DISPLAY INVISIBLE (25 2125);
FORCEPROP 1 LAST BODY_TYPE PLUMBING
J 0
(25 2175);
DISPLAY 0.872340 (25 2175);
PAINT GREEN (25 2175);
DISPLAY INVISIBLE (25 2175);
FORCEPROP 1 LAST HDL_TAP TRUE
J 0
(350 2000);
DISPLAY 0.872340 (350 2000);
DISPLAY INVISIBLE (350 2000);
FORCEPROP 1 LAST PATH I75
J 0
(23 2125);
DISPLAY 0.872340 (23 2125);
PAINT GREEN (23 2125);
DISPLAY INVISIBLE (23 2125);
FORCEADD TAP..1
(25 2175);
FORCEPROP 3 LASTPIN (-25 2175) SIG_NAME M_A_CPU1_SB_DQ<26>
J 0
(-15 2185);
DISPLAY 0.659574 (-15 2185);
PAINT MONO (-15 2185);
DISPLAY INVISIBLE (-15 2185);
FORCEPROP 1 LASTPIN (-25 2175) BN 26
J 0
(-37 2183);
DISPLAY 0.680851 (-37 2183);
PAINT GREEN (-37 2183);
FORCEPROP 2 LAST CDS_LIB standard
J 0
(25 2175);
DISPLAY INVISIBLE (25 2175);
FORCEPROP 1 LAST BODY_TYPE PLUMBING
J 0
(25 2225);
DISPLAY 0.872340 (25 2225);
PAINT GREEN (25 2225);
DISPLAY INVISIBLE (25 2225);
FORCEPROP 1 LAST HDL_TAP TRUE
J 0
(350 2050);
DISPLAY 0.872340 (350 2050);
DISPLAY INVISIBLE (350 2050);
FORCEPROP 1 LAST PATH I76
J 0
(23 2175);
DISPLAY 0.872340 (23 2175);
PAINT GREEN (23 2175);
DISPLAY INVISIBLE (23 2175);
FORCEADD TAP..1
(25 2225);
FORCEPROP 3 LASTPIN (-25 2225) SIG_NAME M_A_CPU1_SB_DQ<27>
J 0
(-15 2235);
DISPLAY 0.659574 (-15 2235);
PAINT MONO (-15 2235);
DISPLAY INVISIBLE (-15 2235);
FORCEPROP 1 LASTPIN (-25 2225) BN 27
J 0
(-37 2233);
DISPLAY 0.680851 (-37 2233);
PAINT GREEN (-37 2233);
FORCEPROP 2 LAST CDS_LIB standard
J 0
(25 2225);
DISPLAY INVISIBLE (25 2225);
FORCEPROP 1 LAST BODY_TYPE PLUMBING
J 0
(25 2275);
DISPLAY 0.872340 (25 2275);
PAINT GREEN (25 2275);
DISPLAY INVISIBLE (25 2275);
FORCEPROP 1 LAST HDL_TAP TRUE
J 0
(350 2100);
DISPLAY 0.872340 (350 2100);
DISPLAY INVISIBLE (350 2100);
FORCEPROP 1 LAST PATH I77
J 0
(23 2225);
DISPLAY 0.872340 (23 2225);
PAINT GREEN (23 2225);
DISPLAY INVISIBLE (23 2225);
FORCEADD TAP..1
(25 2275);
FORCEPROP 3 LASTPIN (-25 2275) SIG_NAME M_A_CPU1_SB_DQ<28>
J 0
(-15 2285);
DISPLAY 0.659574 (-15 2285);
PAINT MONO (-15 2285);
DISPLAY INVISIBLE (-15 2285);
FORCEPROP 1 LASTPIN (-25 2275) BN 28
J 0
(-37 2283);
DISPLAY 0.680851 (-37 2283);
PAINT GREEN (-37 2283);
FORCEPROP 2 LAST CDS_LIB standard
J 0
(25 2275);
DISPLAY INVISIBLE (25 2275);
FORCEPROP 1 LAST BODY_TYPE PLUMBING
J 0
(25 2325);
DISPLAY 0.872340 (25 2325);
PAINT GREEN (25 2325);
DISPLAY INVISIBLE (25 2325);
FORCEPROP 1 LAST HDL_TAP TRUE
J 0
(350 2150);
DISPLAY 0.872340 (350 2150);
DISPLAY INVISIBLE (350 2150);
FORCEPROP 1 LAST PATH I78
J 0
(23 2275);
DISPLAY 0.872340 (23 2275);
PAINT GREEN (23 2275);
DISPLAY INVISIBLE (23 2275);
FORCEADD TAP..1
(25 2325);
FORCEPROP 3 LASTPIN (-25 2325) SIG_NAME M_A_CPU1_SB_DQ<29>
J 0
(-15 2335);
DISPLAY 0.659574 (-15 2335);
PAINT MONO (-15 2335);
DISPLAY INVISIBLE (-15 2335);
FORCEPROP 1 LASTPIN (-25 2325) BN 29
J 0
(-37 2333);
DISPLAY 0.680851 (-37 2333);
PAINT GREEN (-37 2333);
FORCEPROP 2 LAST CDS_LIB standard
J 0
(25 2325);
DISPLAY INVISIBLE (25 2325);
FORCEPROP 1 LAST BODY_TYPE PLUMBING
J 0
(25 2375);
DISPLAY 0.872340 (25 2375);
PAINT GREEN (25 2375);
DISPLAY INVISIBLE (25 2375);
FORCEPROP 1 LAST HDL_TAP TRUE
J 0
(350 2200);
DISPLAY 0.872340 (350 2200);
DISPLAY INVISIBLE (350 2200);
FORCEPROP 1 LAST PATH I79
J 0
(23 2325);
DISPLAY 0.872340 (23 2325);
PAINT GREEN (23 2325);
DISPLAY INVISIBLE (23 2325);
FORCEADD OFFPAGE..1
(-2450 1575);
FORCEPROP 2 LAST $XR0 98 
J 0
(-2911 1575);
DISPLAY 0.638298 (-2911 1575);
PAINT MONO (-2911 1575);
FORCEPROP 2 LAST CDS_LIB standard
J 0
(-2450 1575);
PAINT MONO (-2450 1575);
DISPLAY INVISIBLE (-2450 1575);
FORCEPROP 1 LAST OFFPAGE TRUE
J 0
(-2125 1450);
DISPLAY 0.872340 (-2125 1450);
DISPLAY INVISIBLE (-2125 1450);
FORCEPROP 1 LAST COMMENT_BODY TRUE
J 0
(-2325 1475);
DISPLAY 0.872340 (-2325 1475);
PAINT GREEN (-2325 1475);
DISPLAY INVISIBLE (-2325 1475);
FORCEPROP 2 LAST PATH I8
J 0
(-2400 1650);
DISPLAY 1.021277 (-2400 1650);
DISPLAY INVISIBLE (-2400 1650);
FORCEADD TAP..1
(25 2425);
FORCEPROP 3 LASTPIN (-25 2425) SIG_NAME M_A_CPU1_SB_DQ<31>
J 0
(-15 2435);
DISPLAY 0.659574 (-15 2435);
PAINT MONO (-15 2435);
DISPLAY INVISIBLE (-15 2435);
FORCEPROP 1 LASTPIN (-25 2425) BN 31
J 0
(-37 2433);
DISPLAY 0.680851 (-37 2433);
PAINT GREEN (-37 2433);
FORCEPROP 2 LAST CDS_LIB standard
J 0
(25 2425);
DISPLAY INVISIBLE (25 2425);
FORCEPROP 1 LAST BODY_TYPE PLUMBING
J 0
(25 2475);
DISPLAY 0.872340 (25 2475);
PAINT GREEN (25 2475);
DISPLAY INVISIBLE (25 2475);
FORCEPROP 1 LAST HDL_TAP TRUE
J 0
(350 2300);
DISPLAY 0.872340 (350 2300);
DISPLAY INVISIBLE (350 2300);
FORCEPROP 1 LAST PATH I80
J 0
(23 2425);
DISPLAY 0.872340 (23 2425);
PAINT GREEN (23 2425);
DISPLAY INVISIBLE (23 2425);
FORCEADD TAP..1
(25 2375);
FORCEPROP 3 LASTPIN (-25 2375) SIG_NAME M_A_CPU1_SB_DQ<30>
J 0
(-15 2385);
DISPLAY 0.659574 (-15 2385);
PAINT MONO (-15 2385);
DISPLAY INVISIBLE (-15 2385);
FORCEPROP 1 LASTPIN (-25 2375) BN 30
J 0
(-37 2383);
DISPLAY 0.680851 (-37 2383);
PAINT GREEN (-37 2383);
FORCEPROP 2 LAST CDS_LIB standard
J 0
(25 2375);
DISPLAY INVISIBLE (25 2375);
FORCEPROP 1 LAST BODY_TYPE PLUMBING
J 0
(25 2425);
DISPLAY 0.872340 (25 2425);
PAINT GREEN (25 2425);
DISPLAY INVISIBLE (25 2425);
FORCEPROP 1 LAST HDL_TAP TRUE
J 0
(350 2250);
DISPLAY 0.872340 (350 2250);
DISPLAY INVISIBLE (350 2250);
FORCEPROP 1 LAST PATH I81
J 0
(23 2375);
DISPLAY 0.872340 (23 2375);
PAINT GREEN (23 2375);
DISPLAY INVISIBLE (23 2375);
FORCEADD TAP..1
(25 2525);
FORCEPROP 3 LASTPIN (-25 2525) SIG_NAME M_A_CPU1_SA_DQ<0>
J 0
(-15 2535);
DISPLAY 0.659574 (-15 2535);
PAINT MONO (-15 2535);
DISPLAY INVISIBLE (-15 2535);
FORCEPROP 1 LASTPIN (-25 2525) BN 0
J 0
(-37 2533);
DISPLAY 0.680851 (-37 2533);
PAINT GREEN (-37 2533);
FORCEPROP 2 LAST CDS_LIB standard
J 0
(25 2525);
PAINT MONO (25 2525);
DISPLAY INVISIBLE (25 2525);
FORCEPROP 1 LAST BODY_TYPE PLUMBING
J 0
(25 2575);
DISPLAY 0.872340 (25 2575);
PAINT GREEN (25 2575);
DISPLAY INVISIBLE (25 2575);
FORCEPROP 1 LAST HDL_TAP TRUE
J 0
(350 2400);
DISPLAY 0.872340 (350 2400);
DISPLAY INVISIBLE (350 2400);
FORCEPROP 1 LAST PATH I82
J 0
(23 2525);
DISPLAY 0.872340 (23 2525);
PAINT GREEN (23 2525);
DISPLAY INVISIBLE (23 2525);
FORCEADD TAP..1
(25 2575);
FORCEPROP 3 LASTPIN (-25 2575) SIG_NAME M_A_CPU1_SA_DQ<1>
J 0
(-15 2585);
DISPLAY 0.659574 (-15 2585);
PAINT MONO (-15 2585);
DISPLAY INVISIBLE (-15 2585);
FORCEPROP 1 LASTPIN (-25 2575) BN 1
J 0
(-37 2583);
DISPLAY 0.680851 (-37 2583);
PAINT GREEN (-37 2583);
FORCEPROP 2 LAST CDS_LIB standard
J 0
(25 2575);
PAINT MONO (25 2575);
DISPLAY INVISIBLE (25 2575);
FORCEPROP 1 LAST BODY_TYPE PLUMBING
J 0
(25 2625);
DISPLAY 0.872340 (25 2625);
PAINT GREEN (25 2625);
DISPLAY INVISIBLE (25 2625);
FORCEPROP 1 LAST HDL_TAP TRUE
J 0
(350 2450);
DISPLAY 0.872340 (350 2450);
DISPLAY INVISIBLE (350 2450);
FORCEPROP 1 LAST PATH I83
J 0
(23 2575);
DISPLAY 0.872340 (23 2575);
PAINT GREEN (23 2575);
DISPLAY INVISIBLE (23 2575);
FORCEADD TAP..1
(25 2625);
FORCEPROP 3 LASTPIN (-25 2625) SIG_NAME M_A_CPU1_SA_DQ<2>
J 0
(-15 2635);
DISPLAY 0.659574 (-15 2635);
PAINT MONO (-15 2635);
DISPLAY INVISIBLE (-15 2635);
FORCEPROP 1 LASTPIN (-25 2625) BN 2
J 0
(-37 2633);
DISPLAY 0.680851 (-37 2633);
PAINT GREEN (-37 2633);
FORCEPROP 2 LAST CDS_LIB standard
J 0
(25 2625);
PAINT MONO (25 2625);
DISPLAY INVISIBLE (25 2625);
FORCEPROP 1 LAST BODY_TYPE PLUMBING
J 0
(25 2675);
DISPLAY 0.872340 (25 2675);
PAINT GREEN (25 2675);
DISPLAY INVISIBLE (25 2675);
FORCEPROP 1 LAST HDL_TAP TRUE
J 0
(350 2500);
DISPLAY 0.872340 (350 2500);
DISPLAY INVISIBLE (350 2500);
FORCEPROP 1 LAST PATH I84
J 0
(23 2625);
DISPLAY 0.872340 (23 2625);
PAINT GREEN (23 2625);
DISPLAY INVISIBLE (23 2625);
FORCEADD TAP..1
(25 2675);
FORCEPROP 3 LASTPIN (-25 2675) SIG_NAME M_A_CPU1_SA_DQ<3>
J 0
(-15 2685);
DISPLAY 0.659574 (-15 2685);
PAINT MONO (-15 2685);
DISPLAY INVISIBLE (-15 2685);
FORCEPROP 1 LASTPIN (-25 2675) BN 3
J 0
(-37 2683);
DISPLAY 0.680851 (-37 2683);
PAINT GREEN (-37 2683);
FORCEPROP 2 LAST CDS_LIB standard
J 0
(25 2675);
PAINT MONO (25 2675);
DISPLAY INVISIBLE (25 2675);
FORCEPROP 1 LAST BODY_TYPE PLUMBING
J 0
(25 2725);
DISPLAY 0.872340 (25 2725);
PAINT GREEN (25 2725);
DISPLAY INVISIBLE (25 2725);
FORCEPROP 1 LAST HDL_TAP TRUE
J 0
(350 2550);
DISPLAY 0.872340 (350 2550);
DISPLAY INVISIBLE (350 2550);
FORCEPROP 1 LAST PATH I85
J 0
(23 2675);
DISPLAY 0.872340 (23 2675);
PAINT GREEN (23 2675);
DISPLAY INVISIBLE (23 2675);
FORCEADD TAP..1
(25 2725);
FORCEPROP 3 LASTPIN (-25 2725) SIG_NAME M_A_CPU1_SA_DQ<4>
J 0
(-15 2735);
DISPLAY 0.659574 (-15 2735);
PAINT MONO (-15 2735);
DISPLAY INVISIBLE (-15 2735);
FORCEPROP 1 LASTPIN (-25 2725) BN 4
J 0
(-37 2733);
DISPLAY 0.680851 (-37 2733);
PAINT GREEN (-37 2733);
FORCEPROP 2 LAST CDS_LIB standard
J 0
(25 2725);
PAINT MONO (25 2725);
DISPLAY INVISIBLE (25 2725);
FORCEPROP 1 LAST BODY_TYPE PLUMBING
J 0
(25 2775);
DISPLAY 0.872340 (25 2775);
PAINT GREEN (25 2775);
DISPLAY INVISIBLE (25 2775);
FORCEPROP 1 LAST HDL_TAP TRUE
J 0
(350 2600);
DISPLAY 0.872340 (350 2600);
DISPLAY INVISIBLE (350 2600);
FORCEPROP 1 LAST PATH I86
J 0
(23 2725);
DISPLAY 0.872340 (23 2725);
PAINT GREEN (23 2725);
DISPLAY INVISIBLE (23 2725);
FORCEADD TAP..1
(25 2775);
FORCEPROP 3 LASTPIN (-25 2775) SIG_NAME M_A_CPU1_SA_DQ<5>
J 0
(-15 2785);
DISPLAY 0.659574 (-15 2785);
PAINT MONO (-15 2785);
DISPLAY INVISIBLE (-15 2785);
FORCEPROP 1 LASTPIN (-25 2775) BN 5
J 0
(-37 2783);
DISPLAY 0.680851 (-37 2783);
PAINT GREEN (-37 2783);
FORCEPROP 2 LAST CDS_LIB standard
J 0
(25 2775);
PAINT MONO (25 2775);
DISPLAY INVISIBLE (25 2775);
FORCEPROP 1 LAST BODY_TYPE PLUMBING
J 0
(25 2825);
DISPLAY 0.872340 (25 2825);
PAINT GREEN (25 2825);
DISPLAY INVISIBLE (25 2825);
FORCEPROP 1 LAST HDL_TAP TRUE
J 0
(350 2650);
DISPLAY 0.872340 (350 2650);
DISPLAY INVISIBLE (350 2650);
FORCEPROP 1 LAST PATH I87
J 0
(23 2775);
DISPLAY 0.872340 (23 2775);
PAINT GREEN (23 2775);
DISPLAY INVISIBLE (23 2775);
FORCEADD TAP..1
(25 2825);
FORCEPROP 3 LASTPIN (-25 2825) SIG_NAME M_A_CPU1_SA_DQ<6>
J 0
(-15 2835);
DISPLAY 0.659574 (-15 2835);
PAINT MONO (-15 2835);
DISPLAY INVISIBLE (-15 2835);
FORCEPROP 1 LASTPIN (-25 2825) BN 6
J 0
(-37 2833);
DISPLAY 0.680851 (-37 2833);
PAINT GREEN (-37 2833);
FORCEPROP 2 LAST CDS_LIB standard
J 0
(25 2825);
PAINT MONO (25 2825);
DISPLAY INVISIBLE (25 2825);
FORCEPROP 1 LAST BODY_TYPE PLUMBING
J 0
(25 2875);
DISPLAY 0.872340 (25 2875);
PAINT GREEN (25 2875);
DISPLAY INVISIBLE (25 2875);
FORCEPROP 1 LAST HDL_TAP TRUE
J 0
(350 2700);
DISPLAY 0.872340 (350 2700);
DISPLAY INVISIBLE (350 2700);
FORCEPROP 1 LAST PATH I88
J 0
(23 2825);
DISPLAY 0.872340 (23 2825);
PAINT GREEN (23 2825);
DISPLAY INVISIBLE (23 2825);
FORCEADD TAP..1
(25 2925);
FORCEPROP 3 LASTPIN (-25 2925) SIG_NAME M_A_CPU1_SA_DQ<8>
J 0
(-15 2935);
DISPLAY 0.659574 (-15 2935);
PAINT MONO (-15 2935);
DISPLAY INVISIBLE (-15 2935);
FORCEPROP 1 LASTPIN (-25 2925) BN 8
J 0
(-37 2933);
DISPLAY 0.680851 (-37 2933);
PAINT GREEN (-37 2933);
FORCEPROP 2 LAST CDS_LIB standard
J 0
(25 2925);
PAINT MONO (25 2925);
DISPLAY INVISIBLE (25 2925);
FORCEPROP 1 LAST BODY_TYPE PLUMBING
J 0
(25 2975);
DISPLAY 0.872340 (25 2975);
PAINT GREEN (25 2975);
DISPLAY INVISIBLE (25 2975);
FORCEPROP 1 LAST HDL_TAP TRUE
J 0
(350 2800);
DISPLAY 0.872340 (350 2800);
DISPLAY INVISIBLE (350 2800);
FORCEPROP 1 LAST PATH I89
J 0
(23 2925);
DISPLAY 0.872340 (23 2925);
PAINT GREEN (23 2925);
DISPLAY INVISIBLE (23 2925);
FORCEADD OFFPAGE..1
(-2575 1825);
FORCEPROP 2 LAST $XR3 101 
J 0
(-2977 1789);
DISPLAY 0.638298 (-2977 1789);
PAINT MONO (-2977 1789);
FORCEPROP 2 LAST $XR2 100 
J 0
(-2857 1789);
DISPLAY 0.638298 (-2857 1789);
PAINT MONO (-2857 1789);
FORCEPROP 2 LAST $XR1 99 
J 0
(-2947 1825);
DISPLAY 0.638298 (-2947 1825);
PAINT MONO (-2947 1825);
FORCEPROP 2 LAST $XR0 130 
J 0
(-2857 1825);
DISPLAY 0.638298 (-2857 1825);
PAINT MONO (-2857 1825);
FORCEPROP 2 LAST CDS_LIB standard
J 0
(-2575 1825);
PAINT MONO (-2575 1825);
DISPLAY INVISIBLE (-2575 1825);
FORCEPROP 1 LAST OFFPAGE TRUE
J 0
(-2250 1700);
DISPLAY 0.872340 (-2250 1700);
DISPLAY INVISIBLE (-2250 1700);
FORCEPROP 1 LAST COMMENT_BODY TRUE
J 0
(-2450 1725);
DISPLAY 0.872340 (-2450 1725);
PAINT GREEN (-2450 1725);
DISPLAY INVISIBLE (-2450 1725);
FORCEPROP 2 LAST PATH I9
J 0
(-2525 1900);
DISPLAY 1.021277 (-2525 1900);
DISPLAY INVISIBLE (-2525 1900);
FORCEADD TAP..1
(25 2875);
FORCEPROP 3 LASTPIN (-25 2875) SIG_NAME M_A_CPU1_SA_DQ<7>
J 0
(-15 2885);
DISPLAY 0.659574 (-15 2885);
PAINT MONO (-15 2885);
DISPLAY INVISIBLE (-15 2885);
FORCEPROP 1 LASTPIN (-25 2875) BN 7
J 0
(-37 2883);
DISPLAY 0.680851 (-37 2883);
PAINT GREEN (-37 2883);
FORCEPROP 2 LAST CDS_LIB standard
J 0
(25 2875);
PAINT MONO (25 2875);
DISPLAY INVISIBLE (25 2875);
FORCEPROP 1 LAST BODY_TYPE PLUMBING
J 0
(25 2925);
DISPLAY 0.872340 (25 2925);
PAINT GREEN (25 2925);
DISPLAY INVISIBLE (25 2925);
FORCEPROP 1 LAST HDL_TAP TRUE
J 0
(350 2750);
DISPLAY 0.872340 (350 2750);
DISPLAY INVISIBLE (350 2750);
FORCEPROP 1 LAST PATH I90
J 0
(23 2875);
DISPLAY 0.872340 (23 2875);
PAINT GREEN (23 2875);
DISPLAY INVISIBLE (23 2875);
FORCEADD TAP..1
(25 2975);
FORCEPROP 3 LASTPIN (-25 2975) SIG_NAME M_A_CPU1_SA_DQ<9>
J 0
(-15 2985);
DISPLAY 0.659574 (-15 2985);
PAINT MONO (-15 2985);
DISPLAY INVISIBLE (-15 2985);
FORCEPROP 1 LASTPIN (-25 2975) BN 9
J 0
(-37 2983);
DISPLAY 0.680851 (-37 2983);
PAINT GREEN (-37 2983);
FORCEPROP 2 LAST CDS_LIB standard
J 0
(25 2975);
PAINT MONO (25 2975);
DISPLAY INVISIBLE (25 2975);
FORCEPROP 1 LAST BODY_TYPE PLUMBING
J 0
(25 3025);
DISPLAY 0.872340 (25 3025);
PAINT GREEN (25 3025);
DISPLAY INVISIBLE (25 3025);
FORCEPROP 1 LAST HDL_TAP TRUE
J 0
(350 2850);
DISPLAY 0.872340 (350 2850);
DISPLAY INVISIBLE (350 2850);
FORCEPROP 1 LAST PATH I91
J 0
(23 2975);
DISPLAY 0.872340 (23 2975);
PAINT GREEN (23 2975);
DISPLAY INVISIBLE (23 2975);
FORCEADD TAP..1
(25 3075);
FORCEPROP 3 LASTPIN (-25 3075) SIG_NAME M_A_CPU1_SA_DQ<11>
J 0
(-15 3085);
DISPLAY 0.659574 (-15 3085);
PAINT MONO (-15 3085);
DISPLAY INVISIBLE (-15 3085);
FORCEPROP 1 LASTPIN (-25 3075) BN 11
J 0
(-37 3083);
DISPLAY 0.680851 (-37 3083);
PAINT GREEN (-37 3083);
FORCEPROP 2 LAST CDS_LIB standard
J 0
(25 3075);
PAINT MONO (25 3075);
DISPLAY INVISIBLE (25 3075);
FORCEPROP 1 LAST BODY_TYPE PLUMBING
J 0
(25 3125);
DISPLAY 0.872340 (25 3125);
PAINT GREEN (25 3125);
DISPLAY INVISIBLE (25 3125);
FORCEPROP 1 LAST HDL_TAP TRUE
J 0
(350 2950);
DISPLAY 0.872340 (350 2950);
DISPLAY INVISIBLE (350 2950);
FORCEPROP 1 LAST PATH I92
J 0
(23 3075);
DISPLAY 0.872340 (23 3075);
PAINT GREEN (23 3075);
DISPLAY INVISIBLE (23 3075);
FORCEADD TAP..1
(25 3025);
FORCEPROP 3 LASTPIN (-25 3025) SIG_NAME M_A_CPU1_SA_DQ<10>
J 0
(-15 3035);
DISPLAY 0.659574 (-15 3035);
PAINT MONO (-15 3035);
DISPLAY INVISIBLE (-15 3035);
FORCEPROP 1 LASTPIN (-25 3025) BN 10
J 0
(-37 3033);
DISPLAY 0.680851 (-37 3033);
PAINT GREEN (-37 3033);
FORCEPROP 2 LAST CDS_LIB standard
J 0
(25 3025);
PAINT MONO (25 3025);
DISPLAY INVISIBLE (25 3025);
FORCEPROP 1 LAST BODY_TYPE PLUMBING
J 0
(25 3075);
DISPLAY 0.872340 (25 3075);
PAINT GREEN (25 3075);
DISPLAY INVISIBLE (25 3075);
FORCEPROP 1 LAST HDL_TAP TRUE
J 0
(350 2900);
DISPLAY 0.872340 (350 2900);
DISPLAY INVISIBLE (350 2900);
FORCEPROP 1 LAST PATH I93
J 0
(23 3025);
DISPLAY 0.872340 (23 3025);
PAINT GREEN (23 3025);
DISPLAY INVISIBLE (23 3025);
FORCEADD TAP..1
(25 3175);
FORCEPROP 3 LASTPIN (-25 3175) SIG_NAME M_A_CPU1_SA_DQ<13>
J 0
(-15 3185);
DISPLAY 0.659574 (-15 3185);
PAINT MONO (-15 3185);
DISPLAY INVISIBLE (-15 3185);
FORCEPROP 1 LASTPIN (-25 3175) BN 13
J 0
(-37 3183);
DISPLAY 0.680851 (-37 3183);
PAINT GREEN (-37 3183);
FORCEPROP 2 LAST CDS_LIB standard
J 0
(25 3175);
PAINT MONO (25 3175);
DISPLAY INVISIBLE (25 3175);
FORCEPROP 1 LAST BODY_TYPE PLUMBING
J 0
(25 3225);
DISPLAY 0.872340 (25 3225);
PAINT GREEN (25 3225);
DISPLAY INVISIBLE (25 3225);
FORCEPROP 1 LAST HDL_TAP TRUE
J 0
(350 3050);
DISPLAY 0.872340 (350 3050);
DISPLAY INVISIBLE (350 3050);
FORCEPROP 1 LAST PATH I94
J 0
(23 3175);
DISPLAY 0.872340 (23 3175);
PAINT GREEN (23 3175);
DISPLAY INVISIBLE (23 3175);
FORCEADD TAP..1
(25 3225);
FORCEPROP 3 LASTPIN (-25 3225) SIG_NAME M_A_CPU1_SA_DQ<14>
J 0
(-15 3235);
DISPLAY 0.659574 (-15 3235);
PAINT MONO (-15 3235);
DISPLAY INVISIBLE (-15 3235);
FORCEPROP 1 LASTPIN (-25 3225) BN 14
J 0
(-37 3233);
DISPLAY 0.680851 (-37 3233);
PAINT GREEN (-37 3233);
FORCEPROP 2 LAST CDS_LIB standard
J 0
(25 3225);
PAINT MONO (25 3225);
DISPLAY INVISIBLE (25 3225);
FORCEPROP 1 LAST BODY_TYPE PLUMBING
J 0
(25 3275);
DISPLAY 0.872340 (25 3275);
PAINT GREEN (25 3275);
DISPLAY INVISIBLE (25 3275);
FORCEPROP 1 LAST HDL_TAP TRUE
J 0
(350 3100);
DISPLAY 0.872340 (350 3100);
DISPLAY INVISIBLE (350 3100);
FORCEPROP 1 LAST PATH I95
J 0
(23 3225);
DISPLAY 0.872340 (23 3225);
PAINT GREEN (23 3225);
DISPLAY INVISIBLE (23 3225);
FORCEADD TAP..1
(25 3125);
FORCEPROP 3 LASTPIN (-25 3125) SIG_NAME M_A_CPU1_SA_DQ<12>
J 0
(-15 3135);
DISPLAY 0.659574 (-15 3135);
PAINT MONO (-15 3135);
DISPLAY INVISIBLE (-15 3135);
FORCEPROP 1 LASTPIN (-25 3125) BN 12
J 0
(-37 3133);
DISPLAY 0.680851 (-37 3133);
PAINT GREEN (-37 3133);
FORCEPROP 2 LAST CDS_LIB standard
J 0
(25 3125);
PAINT MONO (25 3125);
DISPLAY INVISIBLE (25 3125);
FORCEPROP 1 LAST BODY_TYPE PLUMBING
J 0
(25 3175);
DISPLAY 0.872340 (25 3175);
PAINT GREEN (25 3175);
DISPLAY INVISIBLE (25 3175);
FORCEPROP 1 LAST HDL_TAP TRUE
J 0
(350 3000);
DISPLAY 0.872340 (350 3000);
DISPLAY INVISIBLE (350 3000);
FORCEPROP 1 LAST PATH I96
J 0
(23 3125);
DISPLAY 0.872340 (23 3125);
PAINT GREEN (23 3125);
DISPLAY INVISIBLE (23 3125);
FORCEADD TAP..1
(25 3325);
FORCEPROP 3 LASTPIN (-25 3325) SIG_NAME M_A_CPU1_SA_DQ<16>
J 0
(-15 3335);
DISPLAY 0.659574 (-15 3335);
PAINT MONO (-15 3335);
DISPLAY INVISIBLE (-15 3335);
FORCEPROP 1 LASTPIN (-25 3325) BN 16
J 0
(-37 3333);
DISPLAY 0.680851 (-37 3333);
PAINT GREEN (-37 3333);
FORCEPROP 2 LAST CDS_LIB standard
J 0
(25 3325);
PAINT MONO (25 3325);
DISPLAY INVISIBLE (25 3325);
FORCEPROP 1 LAST BODY_TYPE PLUMBING
J 0
(25 3375);
DISPLAY 0.872340 (25 3375);
PAINT GREEN (25 3375);
DISPLAY INVISIBLE (25 3375);
FORCEPROP 1 LAST HDL_TAP TRUE
J 0
(350 3200);
DISPLAY 0.872340 (350 3200);
DISPLAY INVISIBLE (350 3200);
FORCEPROP 1 LAST PATH I97
J 0
(23 3325);
DISPLAY 0.872340 (23 3325);
PAINT GREEN (23 3325);
DISPLAY INVISIBLE (23 3325);
FORCEADD TAP..1
(25 3275);
FORCEPROP 3 LASTPIN (-25 3275) SIG_NAME M_A_CPU1_SA_DQ<15>
J 0
(-15 3285);
DISPLAY 0.659574 (-15 3285);
PAINT MONO (-15 3285);
DISPLAY INVISIBLE (-15 3285);
FORCEPROP 1 LASTPIN (-25 3275) BN 15
J 0
(-37 3283);
DISPLAY 0.680851 (-37 3283);
PAINT GREEN (-37 3283);
FORCEPROP 2 LAST CDS_LIB standard
J 0
(25 3275);
PAINT MONO (25 3275);
DISPLAY INVISIBLE (25 3275);
FORCEPROP 1 LAST BODY_TYPE PLUMBING
J 0
(25 3325);
DISPLAY 0.872340 (25 3325);
PAINT GREEN (25 3325);
DISPLAY INVISIBLE (25 3325);
FORCEPROP 1 LAST HDL_TAP TRUE
J 0
(350 3150);
DISPLAY 0.872340 (350 3150);
DISPLAY INVISIBLE (350 3150);
FORCEPROP 1 LAST PATH I98
J 0
(23 3275);
DISPLAY 0.872340 (23 3275);
PAINT GREEN (23 3275);
DISPLAY INVISIBLE (23 3275);
FORCEADD TAP..1
(25 3475);
FORCEPROP 3 LASTPIN (-25 3475) SIG_NAME M_A_CPU1_SA_DQ<19>
J 0
(-15 3485);
DISPLAY 0.659574 (-15 3485);
PAINT MONO (-15 3485);
DISPLAY INVISIBLE (-15 3485);
FORCEPROP 1 LASTPIN (-25 3475) BN 19
J 0
(-37 3483);
DISPLAY 0.680851 (-37 3483);
PAINT GREEN (-37 3483);
FORCEPROP 2 LAST CDS_LIB standard
J 0
(25 3475);
PAINT MONO (25 3475);
DISPLAY INVISIBLE (25 3475);
FORCEPROP 1 LAST BODY_TYPE PLUMBING
J 0
(25 3525);
DISPLAY 0.872340 (25 3525);
PAINT GREEN (25 3525);
DISPLAY INVISIBLE (25 3525);
FORCEPROP 1 LAST HDL_TAP TRUE
J 0
(350 3350);
DISPLAY 0.872340 (350 3350);
DISPLAY INVISIBLE (350 3350);
FORCEPROP 1 LAST PATH I99
J 0
(23 3475);
DISPLAY 0.872340 (23 3475);
PAINT GREEN (23 3475);
DISPLAY INVISIBLE (23 3475);
FORCEADD CAD_NOTE..1
(1875 -375);
FORCEPROP 0 LAST S1 PLACE THE BYPASS CAPS CLOSE TO DIMM
J 0
(1750 -500);
DISPLAY 1.021277 (1750 -500);
PAINT WHITE (1750 -500);
FORCEPROP 2 LAST CDS_LIB logical_power
J 0
(1875 -375);
PAINT MONO (1875 -375);
DISPLAY INVISIBLE (1875 -375);
FORCEPROP 1 LAST COMMENT_BODY TRUE
J 0
(1900 -275);
DISPLAY 0.978723 (1900 -275);
DISPLAY INVISIBLE (1900 -275);
FORCEADD QUANTA_TITLE_BLOCK_C..1
(6350 -1675);
FORCEPROP 0 LAST CDS_CON_LAST_MODIFIED Fri Aug 25 14:01:18 2023
J 0
(4465 -1660);
PAINT MONO (4465 -1660);
DISPLAY INVISIBLE (4465 -1660);
FORCEPROP 2 LAST CUSTOM_TXT_CDS <XR_PAGE_TITLE>
J 0
(-1540 3575);
DISPLAY 0.638298 (-1540 3575);
PAINT PINK (-1540 3575);
DISPLAY INVISIBLE (-1540 3575);
FORCEPROP 2 LAST CUSTOM_TXT_CDS <NAME_2>
J 0
(3175 -1625);
FORCEPROP 2 LAST CUSTOM_TXT_CDS <NAME_1>
J 0
(3175 -1500);
FORCEPROP 2 LAST CUSTOM_TXT_CDS <Q_PROJ>
J 0
(3968 -1573);
DISPLAY 1.212766 (3968 -1573);
FORCEPROP 2 LAST CUSTOM_TXT_CDS <CON_LAST_MODIFIED>
J 0
(4465 -1660);
DISPLAY 0.978723 (4465 -1660);
FORCEPROP 2 LAST CUSTOM_TXT_CDS <Q_NUMBER>
J 0
(4947 -1572);
DISPLAY 1.212766 (4947 -1572);
FORCEPROP 2 LAST CUSTOM_TXT_CDS <CON_PAGE_NUM> OF <CON_TOTAL_PAGES>
J 0
(5904 -1657);
DISPLAY 0.978723 (5904 -1657);
FORCEPROP 2 LAST CUSTOM_TXT_CDS <Q_REV>
J 0
(6166 -1572);
DISPLAY 1.212766 (6166 -1572);
FORCEPROP 1 LAST Q_TITLE DDR5 - CPU1 CHA DIMM1(YELLOW)
J 0
(-3016 -1649);
DISPLAY 2.446809 (-3016 -1649);
PAINT GREEN (-3016 -1649);
FORCEPROP 1 LAST Q_DEPT 
J 1
(2587 -1626);
DISPLAY 1.957447 (2587 -1626);
PAINT GREEN (2587 -1626);
FORCEPROP 1 LAST COMMENT_BODY TRUE
J 0
(6362 -1688);
DISPLAY 0.978723 (6362 -1688);
PAINT GREEN (6362 -1688);
DISPLAY INVISIBLE (6362 -1688);
FORCEPROP 2 LAST CDS_XR_PAGE_TITLE CR-98 : @S9S_MB_2U_LIB.S9S_MB_2U(SCH_1):PAGE98
J 0
(-1540 3575);
DISPLAY 0.638298 (-1540 3575);
PAINT PINK (-1540 3575);
DISPLAY INVISIBLE (-1540 3575);
FORCEPROP 2 LAST CDS_LIB pure_quanta
J 0
(6350 -1675);
PAINT MONO (6350 -1675);
DISPLAY INVISIBLE (6350 -1675);
FORCEPROP 1 LAST CDS_LMAN_SYM_OUTLINE -9475,6775,100,-125
J 0
(6350 -1675);
DISPLAY 0.468085 (6350 -1675);
PAINT GREEN (6350 -1675);
DISPLAY INVISIBLE (6350 -1675);
FORCEPROP 2 LAST PAGE_BORDER TRUE
J 0
(-1540 3575);
DISPLAY 0.638298 (-1540 3575);
PAINT PINK (-1540 3575);
DISPLAY INVISIBLE (-1540 3575);
WIRE 17 -1 (75 4050)(75 4100);
WIRE 17 -1 (75 4000)(75 4050);
WIRE 17 -1 (75 4100)(800 4100);
FORCEPROP 2 LAST SIG_NAME M_A_CPU1_SA_DQ<31:0>
J 0
(140 4110);
DISPLAY 0.680851 (140 4110);
PAINT WHITE (140 4110);
WIRE 17 -1 (-1675 2650)(-1675 2700);
WIRE 17 -1 (-1675 2600)(-1675 2650);
WIRE 17 -1 (-2500 2700)(-1675 2700);
FORCEPROP 2 LAST SIG_NAME M_A_CPU1_SA_CB<7:0>
J 0
(-2410 2710);
DISPLAY 0.680851 (-2410 2710);
PAINT WHITE (-2410 2710);
WIRE 17 -1 (-1675 2550)(-1675 2600);
WIRE 17 -1 (-1675 2500)(-1675 2550);
WIRE 17 -1 (-1675 2450)(-1675 2500);
WIRE 17 -1 (-1675 2400)(-1675 2450);
WIRE 17 -1 (-1675 2350)(-1675 2400);
WIRE 17 -1 (-1675 2200)(-1675 2250);
WIRE 17 -1 (-1675 2150)(-1675 2200);
WIRE 17 -1 (-2500 2250)(-1675 2250);
FORCEPROP 2 LAST SIG_NAME M_A_CPU1_SB_CB<7:0>
J 0
(-2410 2260);
DISPLAY 0.680851 (-2410 2260);
PAINT WHITE (-2410 2260);
WIRE 17 -1 (-1675 3800)(-1675 3850);
WIRE 17 -1 (-1675 3850)(-1675 3900);
WIRE 17 -1 (-1675 3900)(-1675 3950);
WIRE 17 -1 (-1675 3950)(-1675 4000);
WIRE 17 -1 (-1675 4000)(-1675 4050);
WIRE 17 -1 (-1675 4050)(-1675 4100);
WIRE 17 -1 (-2500 4100)(-1675 4100);
FORCEPROP 2 LAST SIG_NAME M_A_CPU1_SA_CA<6:0>
J 0
(-2410 4110);
DISPLAY 0.680851 (-2410 4110);
PAINT WHITE (-2410 4110);
WIRE 17 -1 (-1675 3400)(-1675 3450);
WIRE 17 -1 (-1675 3450)(-1675 3500);
WIRE 17 -1 (-1675 3500)(-1675 3550);
WIRE 17 -1 (-1675 3550)(-1675 3600);
WIRE 17 -1 (-1675 3600)(-1675 3650);
WIRE 17 -1 (-1675 3650)(-1675 3700);
WIRE 17 -1 (-2500 3700)(-1675 3700);
FORCEPROP 2 LAST SIG_NAME M_A_CPU1_SB_CA<6:0>
J 0
(-2410 3710);
DISPLAY 0.680851 (-2410 3710);
PAINT WHITE (-2410 3710);
WIRE 17 -1 (-1675 2100)(-1675 2150);
WIRE 17 -1 (-1675 2050)(-1675 2100);
WIRE 17 -1 (-1675 2000)(-1675 2050);
WIRE 17 -1 (-1675 1950)(-1675 2000);
WIRE 17 -1 (75 3950)(75 4000);
WIRE 17 -1 (75 3900)(75 3950);
WIRE 17 -1 (75 3850)(75 3900);
WIRE 17 -1 (75 3800)(75 3850);
WIRE 17 -1 (75 3750)(75 3800);
WIRE 17 -1 (75 3700)(75 3750);
WIRE 17 -1 (75 3650)(75 3700);
WIRE 17 -1 (75 3600)(75 3650);
WIRE 17 -1 (75 3550)(75 3600);
WIRE 17 -1 (75 3500)(75 3550);
WIRE 17 -1 (75 3450)(75 3500);
WIRE 17 -1 (75 3400)(75 3450);
WIRE 17 -1 (75 3350)(75 3400);
WIRE 17 -1 (75 3300)(75 3350);
WIRE 17 -1 (75 3250)(75 3300);
WIRE 17 -1 (75 3200)(75 3250);
WIRE 17 -1 (75 3150)(75 3200);
WIRE 17 -1 (75 3100)(75 3150);
WIRE 17 -1 (75 3050)(75 3100);
WIRE 17 -1 (75 3000)(75 3050);
WIRE 17 -1 (75 2950)(75 3000);
WIRE 17 -1 (75 2900)(75 2950);
WIRE 17 -1 (75 2850)(75 2900);
WIRE 17 -1 (75 2800)(75 2850);
WIRE 17 -1 (75 2750)(75 2800);
WIRE 17 -1 (75 2700)(75 2750);
WIRE 17 -1 (75 2650)(75 2700);
WIRE 17 -1 (75 2600)(75 2650);
WIRE 17 -1 (75 2550)(75 2600);
WIRE 17 -1 (75 2400)(75 2450);
WIRE 17 -1 (75 2350)(75 2400);
WIRE 17 -1 (75 2450)(800 2450);
FORCEPROP 2 LAST SIG_NAME M_A_CPU1_SB_DQ<31:0>
J 0
(140 2460);
DISPLAY 0.680851 (140 2460);
PAINT WHITE (140 2460);
WIRE 17 -1 (75 2300)(75 2350);
WIRE 17 -1 (75 2250)(75 2300);
WIRE 17 -1 (75 2200)(75 2250);
WIRE 17 -1 (75 2150)(75 2200);
WIRE 17 -1 (75 2100)(75 2150);
WIRE 17 -1 (75 2050)(75 2100);
WIRE 17 -1 (75 2000)(75 2050);
WIRE 17 -1 (75 1950)(75 2000);
WIRE 17 -1 (75 1900)(75 1950);
WIRE 17 -1 (75 1850)(75 1900);
WIRE 17 -1 (75 1800)(75 1850);
WIRE 17 -1 (75 1750)(75 1800);
WIRE 17 -1 (75 1700)(75 1750);
WIRE 17 -1 (75 1650)(75 1700);
WIRE 17 -1 (75 1600)(75 1650);
WIRE 17 -1 (75 1550)(75 1600);
WIRE 17 -1 (75 1500)(75 1550);
WIRE 17 -1 (75 1450)(75 1500);
WIRE 17 -1 (75 1400)(75 1450);
WIRE 17 -1 (75 1350)(75 1400);
WIRE 17 -1 (75 1300)(75 1350);
WIRE 17 -1 (75 1250)(75 1300);
WIRE 17 -1 (75 1200)(75 1250);
WIRE 17 -1 (75 1150)(75 1200);
WIRE 17 -1 (75 1100)(75 1150);
WIRE 17 -1 (75 1050)(75 1100);
WIRE 17 -1 (75 1000)(75 1050);
WIRE 17 -1 (75 950)(75 1000);
WIRE 17 -1 (75 900)(75 950);
WIRE 17 -1 (-1675 1900)(-1675 1950);
WIRE 17 -1 (2825 2150)(2825 2250);
WIRE 17 -1 (2825 2250)(2825 2350);
WIRE 17 -1 (2825 2350)(2825 2450);
WIRE 17 -1 (2825 2550)(2825 2450);
WIRE 17 -1 (2825 2550)(2825 2650);
WIRE 17 -1 (2825 2650)(2825 2750);
WIRE 17 -1 (2825 2750)(2825 2850);
WIRE 17 -1 (2825 2850)(2825 2950);
WIRE 17 -1 (2825 2950)(2825 3050);
WIRE 17 -1 (2825 3050)(3850 3050);
FORCEPROP 2 LAST SIG_NAME M_A_CPU1_SB_DQS_DP<9:0>
J 0
(3065 3060);
DISPLAY 0.680851 (3065 3060);
PAINT WHITE (3065 3060);
WIRE 17 -1 (2825 3200)(2825 3300);
WIRE 17 -1 (2825 3300)(2825 3400);
WIRE 17 -1 (2825 3400)(2825 3500);
WIRE 17 -1 (2825 3600)(2825 3500);
WIRE 17 -1 (2825 3600)(2825 3700);
WIRE 17 -1 (2825 3700)(2825 3800);
WIRE 17 -1 (2825 3800)(2825 3900);
WIRE 17 -1 (2825 3900)(2825 4000);
WIRE 17 -1 (2825 4000)(2825 4100);
WIRE 17 -1 (2825 4100)(3850 4100);
FORCEPROP 2 LAST SIG_NAME M_A_CPU1_SA_DQS_DP<9:0>
J 0
(3065 4110);
DISPLAY 0.680851 (3065 4110);
PAINT WHITE (3065 4110);
WIRE 17 -1 (3000 2200)(3000 2300);
WIRE 17 -1 (3000 2100)(3000 2200);
WIRE 17 -1 (3000 2300)(3000 2400);
WIRE 17 -1 (3000 2500)(3000 2400);
WIRE 17 -1 (3000 2500)(3000 2600);
WIRE 17 -1 (3000 2600)(3000 2700);
WIRE 17 -1 (3000 2700)(3000 2800);
WIRE 17 -1 (3000 2800)(3000 2900);
WIRE 17 -1 (3000 2900)(3000 3000);
WIRE 17 -1 (3000 3000)(3850 3000);
FORCEPROP 2 LAST SIG_NAME M_A_CPU1_SB_DQS_DN<9:0>
J 0
(3065 3010);
DISPLAY 0.680851 (3065 3010);
PAINT WHITE (3065 3010);
WIRE 17 -1 (3000 3150)(3000 3250);
WIRE 17 -1 (3000 3250)(3000 3350);
WIRE 17 -1 (3000 3350)(3000 3450);
WIRE 17 -1 (3000 3550)(3000 3450);
WIRE 17 -1 (3000 3550)(3000 3650);
WIRE 17 -1 (3000 3650)(3000 3750);
WIRE 17 -1 (3000 3750)(3000 3850);
WIRE 17 -1 (3000 3850)(3000 3950);
WIRE 17 -1 (3000 3950)(3000 4050);
WIRE 17 -1 (3000 4050)(3850 4050);
FORCEPROP 2 LAST SIG_NAME M_A_CPU1_SA_DQS_DN<9:0>
J 0
(3065 4060);
DISPLAY 0.680851 (3065 4060);
PAINT WHITE (3065 4060);
WIRE 16 -1 (-2450 1900)(-2450 1625);
WIRE 16 -1 (4450 4575)(4450 4075);
WIRE 16 -1 (2750 475)(2750 425);
WIRE 16 -1 (1750 300)(1750 475);
WIRE 16 -1 (6150 725)(6150 425);
WIRE 16 -1 (6150 775)(6150 725);
WIRE 16 -1 (5900 725)(6150 725);
WIRE 16 -1 (4450 425)(4450 825);
WIRE 16 -1 (3375 -125)(3375 -50);
WIRE 16 -1 (1750 100)(1750 -125);
WIRE 16 -1 (-1400 -250)(-1400 -175);
WIRE 16 -1 (-2450 1625)(-1400 1625);
WIRE 16 -1 (-1400 1575)(-2400 1575);
FORCEPROP 2 LAST SIG_NAME PD_CHA_CPU1_DIMM1_SAA
J 0
(-2410 1585);
DISPLAY 0.680851 (-2410 1585);
PAINT WHITE (-2410 1585);
WIRE 16 -1 (-1400 1525)(-2400 1525);
FORCEPROP 2 LAST SIG_NAME I3C_SPD_DDRABCD_CPU1_LVC1_SDA
J 0
(-2410 1535);
DISPLAY 0.680851 (-2410 1535);
PAINT WHITE (-2410 1535);
WIRE 16 -1 (-2925 1350)(-2725 1350);
WIRE 16 -1 (-2925 1350)(-2925 1475);
WIRE 16 -1 (-1400 1475)(-2925 1475);
FORCEPROP 2 LAST SIG_NAME I3C_SPD_DDRABCD_CPU1_LVC1_SCL_R1
J 0
(-2460 1485);
DISPLAY 0.680851 (-2460 1485);
PAINT WHITE (-2460 1485);
WIRE 16 -1 (-1400 1725)(-2500 1725);
FORCEPROP 2 LAST SIG_NAME M_A_CPU1_ALERT_N
J 0
(-2412 1734);
DISPLAY 0.680851 (-2412 1734);
PAINT WHITE (-2412 1734);
WIRE 16 -1 (-1800 1825)(-2525 1825);
FORCEPROP 2 LAST SIG_NAME RST_M_AB_CPU1_FPGA_N
J 0
(-2437 1834);
DISPLAY 0.680851 (-2437 1834);
PAINT WHITE (-2437 1834);
WIRE 16 -1 (-1800 1825)(-1800 1775);
WIRE 16 -1 (-1800 1775)(-1400 1775);
WIRE 16 -1 (-1275 1300)(-1300 1300);
WIRE 16 -1 (-2525 1350)(-1275 1350);
FORCEPROP 2 LAST SIG_NAME I3C_SPD_DDRABCD_CPU1_LVC1_SCL
J 0
(-2310 1360);
DISPLAY 0.680851 (-2310 1360);
PAINT WHITE (-2310 1360);
WIRE 16 -1 (-1275 1350)(-1275 1300);
WIRE 16 -1 (-1400 1225)(-2500 1225);
FORCEPROP 2 LAST SIG_NAME PWRGD_CHA_CPU1_DIMM1
J 0
(-2412 1234);
DISPLAY 0.680851 (-2412 1234);
PAINT WHITE (-2412 1234);
WIRE 16 -1 (-1575 1875)(-1400 1875);
WIRE 16 -1 (-1575 1925)(-1400 1925);
WIRE 16 -1 (-1400 2975)(-2500 2975);
FORCEPROP 2 LAST SIG_NAME M_A_CPU1_SB_CS_N<1>
J 0
(-2412 2984);
DISPLAY 0.680851 (-2412 2984);
PAINT WHITE (-2412 2984);
WIRE 16 -1 (-1400 3075)(-2500 3075);
FORCEPROP 2 LAST SIG_NAME M_A_CPU1_SA_CS_N<0>
J 0
(-2412 3084);
DISPLAY 0.680851 (-2412 3084);
PAINT WHITE (-2412 3084);
WIRE 16 -1 (2625 2675)(2900 2675);
WIRE 16 -1 (2625 4025)(2900 4025);
WIRE 16 -1 (2625 3925)(2900 3925);
WIRE 16 -1 (2625 3725)(2900 3725);
WIRE 16 -1 (2625 3825)(2900 3825);
WIRE 16 -1 (2625 3625)(2900 3625);
WIRE 16 -1 (2625 3525)(2900 3525);
WIRE 16 -1 (2625 3425)(2900 3425);
WIRE 16 -1 (2625 3225)(2900 3225);
WIRE 16 -1 (2625 3325)(2900 3325);
WIRE 16 -1 (2625 3125)(2900 3125);
WIRE 16 -1 (2625 2975)(2900 2975);
WIRE 16 -1 (2625 2875)(2900 2875);
WIRE 16 -1 (2625 2775)(2900 2775);
WIRE 16 -1 (2625 2575)(2900 2575);
WIRE 16 -1 (2625 2475)(2900 2475);
WIRE 16 -1 (2625 2375)(2900 2375);
WIRE 16 -1 (2625 2275)(2900 2275);
WIRE 16 -1 (2625 2075)(2900 2075);
WIRE 16 -1 (2625 2175)(2900 2175);
WIRE 16 -1 (2625 4075)(2725 4075);
WIRE 16 -1 (2625 3975)(2725 3975);
WIRE 16 -1 (2625 3875)(2725 3875);
WIRE 16 -1 (2625 3775)(2725 3775);
WIRE 16 -1 (2625 3675)(2725 3675);
WIRE 16 -1 (2625 3575)(2725 3575);
WIRE 16 -1 (2625 3475)(2725 3475);
WIRE 16 -1 (2625 3375)(2725 3375);
WIRE 16 -1 (2625 3275)(2725 3275);
WIRE 16 -1 (2625 3175)(2725 3175);
WIRE 16 -1 (2625 3025)(2725 3025);
WIRE 16 -1 (2625 2925)(2725 2925);
WIRE 16 -1 (2625 2825)(2725 2825);
WIRE 16 -1 (2625 2725)(2725 2725);
WIRE 16 -1 (2625 2625)(2725 2625);
WIRE 16 -1 (2625 2525)(2725 2525);
WIRE 16 -1 (2625 2425)(2725 2425);
WIRE 16 -1 (2625 2325)(2725 2325);
WIRE 16 -1 (2625 2225)(2725 2225);
WIRE 16 -1 (2625 2125)(2725 2125);
WIRE 16 -1 (-1575 2425)(-1400 2425);
WIRE 16 -1 (-1400 1125)(-2500 1125);
FORCEPROP 2 LAST SIG_NAME TP_CHA_CPU1_DIMM1_FRU_6
J 0
(-2412 1134);
DISPLAY 0.680851 (-2412 1134);
PAINT WHITE (-2412 1134);
WIRE 16 -1 (-1400 1075)(-2500 1075);
FORCEPROP 2 LAST SIG_NAME TP_CHA_CPU1_DIMM1_FRU_5
J 0
(-2412 1084);
DISPLAY 0.680851 (-2412 1084);
PAINT WHITE (-2412 1084);
WIRE 16 -1 (-1400 1025)(-2500 1025);
FORCEPROP 2 LAST SIG_NAME TP_CHA_CPU1_DIMM1_FRU_4
J 0
(-2412 1034);
DISPLAY 0.680851 (-2412 1034);
PAINT WHITE (-2412 1034);
WIRE 16 -1 (-1575 1975)(-1400 1975);
WIRE 16 -1 (-1575 2025)(-1400 2025);
WIRE 16 -1 (4700 4075)(4450 4075);
WIRE 16 -1 (4450 4075)(4450 4025);
WIRE 16 -1 (4450 4025)(4700 4025);
WIRE 16 -1 (4450 4025)(4450 3975);
WIRE 16 -1 (4700 3975)(4450 3975);
WIRE 16 -1 (4450 825)(4700 825);
WIRE 16 -1 (4450 825)(4450 875);
WIRE 16 -1 (4450 875)(4700 875);
WIRE 16 -1 (4450 875)(4450 925);
WIRE 16 -1 (4450 925)(4700 925);
WIRE 16 -1 (4450 925)(4450 975);
WIRE 16 -1 (4450 975)(4700 975);
WIRE 16 -1 (4450 975)(4450 1025);
WIRE 16 -1 (4450 1025)(4700 1025);
WIRE 16 -1 (4450 1025)(4450 1075);
WIRE 16 -1 (4450 1075)(4700 1075);
WIRE 16 -1 (4450 1075)(4450 1125);
WIRE 16 -1 (4450 1125)(4700 1125);
WIRE 16 -1 (4450 1125)(4450 1175);
WIRE 16 -1 (4450 1175)(4700 1175);
WIRE 16 -1 (4450 1175)(4450 1225);
WIRE 16 -1 (4450 1225)(4700 1225);
WIRE 16 -1 (4450 1225)(4450 1275);
WIRE 16 -1 (4450 1275)(4700 1275);
WIRE 16 -1 (4450 1275)(4450 1325);
WIRE 16 -1 (4700 1325)(4450 1325);
WIRE 16 -1 (4450 1325)(4450 1375);
WIRE 16 -1 (4450 1375)(4700 1375);
WIRE 16 -1 (4450 1375)(4450 1425);
WIRE 16 -1 (4450 1425)(4700 1425);
WIRE 16 -1 (4450 1425)(4450 1475);
WIRE 16 -1 (4450 1475)(4700 1475);
WIRE 16 -1 (4450 1475)(4450 1525);
WIRE 16 -1 (4450 1525)(4700 1525);
WIRE 16 -1 (4450 1525)(4450 1575);
WIRE 16 -1 (4450 1575)(4700 1575);
WIRE 16 -1 (4450 1575)(4450 1625);
WIRE 16 -1 (4450 1625)(4700 1625);
WIRE 16 -1 (4450 1625)(4450 1675);
WIRE 16 -1 (4450 1675)(4700 1675);
WIRE 16 -1 (4450 1675)(4450 1725);
WIRE 16 -1 (4450 1725)(4700 1725);
WIRE 16 -1 (4450 1725)(4450 1775);
WIRE 16 -1 (4450 1775)(4700 1775);
WIRE 16 -1 (4450 1775)(4450 1825);
WIRE 16 -1 (4700 1825)(4450 1825);
WIRE 16 -1 (4450 1825)(4450 1875);
WIRE 16 -1 (4450 1875)(4700 1875);
WIRE 16 -1 (4450 1875)(4450 1925);
WIRE 16 -1 (4450 1925)(4700 1925);
WIRE 16 -1 (4450 1925)(4450 1975);
WIRE 16 -1 (4450 1975)(4700 1975);
WIRE 16 -1 (4450 1975)(4450 2025);
WIRE 16 -1 (4450 2025)(4700 2025);
WIRE 16 -1 (4450 2025)(4450 2075);
WIRE 16 -1 (4450 2075)(4700 2075);
WIRE 16 -1 (4450 2075)(4450 2125);
WIRE 16 -1 (4450 2125)(4700 2125);
WIRE 16 -1 (4450 2125)(4450 2175);
WIRE 16 -1 (4450 2175)(4700 2175);
WIRE 16 -1 (4450 2175)(4450 2225);
WIRE 16 -1 (4450 2225)(4700 2225);
WIRE 16 -1 (4450 2225)(4450 2275);
WIRE 16 -1 (4450 2275)(4700 2275);
WIRE 16 -1 (4450 2275)(4450 2325);
WIRE 16 -1 (4700 2325)(4450 2325);
WIRE 16 -1 (4450 2325)(4450 2375);
WIRE 16 -1 (4450 2375)(4700 2375);
WIRE 16 -1 (4450 2375)(4450 2425);
WIRE 16 -1 (4450 2425)(4700 2425);
WIRE 16 -1 (4450 2425)(4450 2475);
WIRE 16 -1 (4450 2475)(4700 2475);
WIRE 16 -1 (4450 2475)(4450 2525);
WIRE 16 -1 (4450 2525)(4700 2525);
WIRE 16 -1 (4450 2525)(4450 2575);
WIRE 16 -1 (4450 2575)(4700 2575);
WIRE 16 -1 (4450 2575)(4450 2625);
WIRE 16 -1 (4450 2625)(4700 2625);
WIRE 16 -1 (4450 2625)(4450 2675);
WIRE 16 -1 (4450 2675)(4700 2675);
WIRE 16 -1 (4450 2675)(4450 2725);
WIRE 16 -1 (4450 2725)(4700 2725);
WIRE 16 -1 (4450 2725)(4450 2775);
WIRE 16 -1 (4450 2775)(4700 2775);
WIRE 16 -1 (4450 2775)(4450 2825);
WIRE 16 -1 (4700 2825)(4450 2825);
WIRE 16 -1 (4450 2825)(4450 2875);
WIRE 16 -1 (4450 2875)(4700 2875);
WIRE 16 -1 (4450 2875)(4450 2925);
WIRE 16 -1 (4450 2925)(4700 2925);
WIRE 16 -1 (4450 2925)(4450 2975);
WIRE 16 -1 (4450 2975)(4700 2975);
WIRE 16 -1 (4450 2975)(4450 3025);
WIRE 16 -1 (4450 3025)(4700 3025);
WIRE 16 -1 (4450 3025)(4450 3075);
WIRE 16 -1 (4450 3075)(4700 3075);
WIRE 16 -1 (4450 3075)(4450 3125);
WIRE 16 -1 (4450 3125)(4700 3125);
WIRE 16 -1 (4450 3125)(4450 3175);
WIRE 16 -1 (4450 3175)(4700 3175);
WIRE 16 -1 (4450 3175)(4450 3225);
WIRE 16 -1 (4450 3225)(4700 3225);
WIRE 16 -1 (4450 3225)(4450 3275);
WIRE 16 -1 (4450 3275)(4700 3275);
WIRE 16 -1 (4450 3275)(4450 3325);
WIRE 16 -1 (4700 3325)(4450 3325);
WIRE 16 -1 (4450 3325)(4450 3375);
WIRE 16 -1 (4450 3375)(4700 3375);
WIRE 16 -1 (4450 3375)(4450 3425);
WIRE 16 -1 (4450 3425)(4700 3425);
WIRE 16 -1 (4450 3425)(4450 3475);
WIRE 16 -1 (4450 3475)(4700 3475);
WIRE 16 -1 (4450 3475)(4450 3525);
WIRE 16 -1 (4450 3525)(4700 3525);
WIRE 16 -1 (4450 3525)(4450 3575);
WIRE 16 -1 (4450 3575)(4700 3575);
WIRE 16 -1 (4450 3575)(4450 3625);
WIRE 16 -1 (4450 3625)(4700 3625);
WIRE 16 -1 (4450 3625)(4450 3675);
WIRE 16 -1 (4450 3675)(4700 3675);
WIRE 16 -1 (4450 3675)(4450 3725);
WIRE 16 -1 (4450 3725)(4700 3725);
WIRE 16 -1 (4450 3725)(4450 3775);
WIRE 16 -1 (4450 3775)(4700 3775);
WIRE 16 -1 (4450 3775)(4450 3825);
WIRE 16 -1 (4700 3825)(4450 3825);
WIRE 16 -1 (4450 3825)(4450 3875);
WIRE 16 -1 (4450 3875)(4700 3875);
WIRE 16 -1 (4450 3875)(4450 3925);
WIRE 16 -1 (4700 3925)(4450 3925);
WIRE 16 -1 (-200 1325)(-25 1325);
WIRE 16 -1 (-200 1275)(-25 1275);
WIRE 16 -1 (-1400 3275)(-2500 3275);
FORCEPROP 2 LAST SIG_NAME M_A_CPU1_SA_PAR
J 0
(-2412 3284);
DISPLAY 0.680851 (-2412 3284);
PAINT WHITE (-2412 3284);
WIRE 16 -1 (-1400 3225)(-2500 3225);
FORCEPROP 2 LAST SIG_NAME M_A_CPU1_SB_PAR
J 0
(-2412 3234);
DISPLAY 0.680851 (-2412 3234);
PAINT WHITE (-2412 3234);
WIRE 16 -1 (-1575 3675)(-1400 3675);
WIRE 16 -1 (-1400 2775)(-2500 2775);
FORCEPROP 2 LAST SIG_NAME M_A_CPU1_CLK_DN<0>
J 0
(-2412 2784);
DISPLAY 0.680851 (-2412 2784);
PAINT WHITE (-2412 2784);
WIRE 16 -1 (-1400 2825)(-2500 2825);
FORCEPROP 2 LAST SIG_NAME M_A_CPU1_CLK_DP<0>
J 0
(-2412 2834);
DISPLAY 0.680851 (-2412 2834);
PAINT WHITE (-2412 2834);
WIRE 16 -1 (-1400 825)(-2500 825);
FORCEPROP 2 LAST SIG_NAME TP_CHA_CPU1_DIMM1_FRU_0
J 0
(-2412 834);
DISPLAY 0.680851 (-2412 834);
PAINT WHITE (-2412 834);
WIRE 16 -1 (-1400 875)(-2500 875);
FORCEPROP 2 LAST SIG_NAME TP_CHA_CPU1_DIMM1_FRU_1
J 0
(-2412 884);
DISPLAY 0.680851 (-2412 884);
PAINT WHITE (-2412 884);
WIRE 16 -1 (-1400 925)(-2500 925);
FORCEPROP 2 LAST SIG_NAME TP_CHA_CPU1_DIMM1_FRU_2
J 0
(-2412 934);
DISPLAY 0.680851 (-2412 934);
PAINT WHITE (-2412 934);
WIRE 16 -1 (-1400 975)(-2500 975);
FORCEPROP 2 LAST SIG_NAME TP_CHA_CPU1_DIMM1_FRU_3
J 0
(-2412 984);
DISPLAY 0.680851 (-2412 984);
PAINT WHITE (-2412 984);
WIRE 16 -1 (-1400 625)(-2500 625);
FORCEPROP 2 LAST SIG_NAME M_A_CPU1_SB_RSP<0>
J 0
(-2412 634);
DISPLAY 0.680851 (-2412 634);
PAINT WHITE (-2412 634);
WIRE 16 -1 (-1400 675)(-2500 675);
FORCEPROP 2 LAST SIG_NAME M_A_CPU1_SA_RSP<0>
J 0
(-2412 684);
DISPLAY 0.680851 (-2412 684);
PAINT WHITE (-2412 684);
WIRE 16 -1 (-200 875)(-25 875);
WIRE 16 -1 (-200 925)(-25 925);
WIRE 16 -1 (-200 975)(-25 975);
WIRE 16 -1 (-200 1025)(-25 1025);
WIRE 16 -1 (-200 1075)(-25 1075);
WIRE 16 -1 (-200 1125)(-25 1125);
WIRE 16 -1 (-200 1175)(-25 1175);
WIRE 16 -1 (-200 1225)(-25 1225);
WIRE 16 -1 (-200 1375)(-25 1375);
WIRE 16 -1 (-200 1425)(-25 1425);
WIRE 16 -1 (-200 1475)(-25 1475);
WIRE 16 -1 (-200 1525)(-25 1525);
WIRE 16 -1 (-200 1575)(-25 1575);
WIRE 16 -1 (-200 1625)(-25 1625);
WIRE 16 -1 (-200 1675)(-25 1675);
WIRE 16 -1 (-200 1725)(-25 1725);
WIRE 16 -1 (-200 1775)(-25 1775);
WIRE 16 -1 (-200 1825)(-25 1825);
WIRE 16 -1 (-200 1875)(-25 1875);
WIRE 16 -1 (-200 1925)(-25 1925);
WIRE 16 -1 (-200 1975)(-25 1975);
WIRE 16 -1 (-200 2025)(-25 2025);
WIRE 16 -1 (-200 2075)(-25 2075);
WIRE 16 -1 (-200 2125)(-25 2125);
WIRE 16 -1 (-200 2175)(-25 2175);
WIRE 16 -1 (-200 2225)(-25 2225);
WIRE 16 -1 (-200 2275)(-25 2275);
WIRE 16 -1 (-200 2325)(-25 2325);
WIRE 16 -1 (-200 2375)(-25 2375);
WIRE 16 -1 (-200 2425)(-25 2425);
WIRE 16 -1 (-200 2525)(-25 2525);
WIRE 16 -1 (-200 2575)(-25 2575);
WIRE 16 -1 (-200 2625)(-25 2625);
WIRE 16 -1 (-200 2675)(-25 2675);
WIRE 16 -1 (-200 2725)(-25 2725);
WIRE 16 -1 (-200 2775)(-25 2775);
WIRE 16 -1 (-200 2825)(-25 2825);
WIRE 16 -1 (-200 2875)(-25 2875);
WIRE 16 -1 (-200 2925)(-25 2925);
WIRE 16 -1 (-200 2975)(-25 2975);
WIRE 16 -1 (-200 3025)(-25 3025);
WIRE 16 -1 (-200 3075)(-25 3075);
WIRE 16 -1 (-200 3125)(-25 3125);
WIRE 16 -1 (-200 3175)(-25 3175);
WIRE 16 -1 (-200 3225)(-25 3225);
WIRE 16 -1 (-200 3275)(-25 3275);
WIRE 16 -1 (-200 3325)(-25 3325);
WIRE 16 -1 (-200 3375)(-25 3375);
WIRE 16 -1 (-200 3425)(-25 3425);
WIRE 16 -1 (-200 3475)(-25 3475);
WIRE 16 -1 (-200 3525)(-25 3525);
WIRE 16 -1 (-200 3575)(-25 3575);
WIRE 16 -1 (-200 3625)(-25 3625);
WIRE 16 -1 (-200 3675)(-25 3675);
WIRE 16 -1 (-200 3725)(-25 3725);
WIRE 16 -1 (-200 3775)(-25 3775);
WIRE 16 -1 (-200 3825)(-25 3825);
WIRE 16 -1 (-200 3875)(-25 3875);
WIRE 16 -1 (-200 3925)(-25 3925);
WIRE 16 -1 (-200 3975)(-25 3975);
WIRE 16 -1 (-200 4025)(-25 4025);
WIRE 16 -1 (-1400 3125)(-2500 3125);
FORCEPROP 2 LAST SIG_NAME M_A_CPU1_SA_CS_N<1>
J 0
(-2412 3134);
DISPLAY 0.680851 (-2412 3134);
PAINT WHITE (-2412 3134);
WIRE 16 -1 (-1400 2925)(-2500 2925);
FORCEPROP 2 LAST SIG_NAME M_A_CPU1_SB_CS_N<0>
J 0
(-2412 2934);
DISPLAY 0.680851 (-2412 2934);
PAINT WHITE (-2412 2934);
WIRE 16 -1 (-1575 2075)(-1400 2075);
WIRE 16 -1 (-1575 2125)(-1400 2125);
WIRE 16 -1 (-1575 2175)(-1400 2175);
WIRE 16 -1 (-1575 2325)(-1400 2325);
WIRE 16 -1 (-1575 2475)(-1400 2475);
WIRE 16 -1 (-1575 2575)(-1400 2575);
WIRE 16 -1 (-1575 2625)(-1400 2625);
WIRE 16 -1 (-1575 4075)(-1400 4075);
WIRE 16 -1 (-1575 3625)(-1400 3625);
WIRE 16 -1 (-1575 4025)(-1400 4025);
WIRE 16 -1 (-1575 3575)(-1400 3575);
WIRE 16 -1 (-1575 3975)(-1400 3975);
WIRE 16 -1 (-1575 3525)(-1400 3525);
WIRE 16 -1 (-1575 3925)(-1400 3925);
WIRE 16 -1 (-1575 3475)(-1400 3475);
WIRE 16 -1 (-1575 3875)(-1400 3875);
WIRE 16 -1 (-1575 3425)(-1400 3425);
WIRE 16 -1 (-1575 3825)(-1400 3825);
WIRE 16 -1 (-1575 3375)(-1400 3375);
WIRE 16 -1 (-1575 3775)(-1400 3775);
WIRE 16 -1 (-1575 2225)(-1400 2225);
WIRE 16 -1 (-1575 2375)(-1400 2375);
WIRE 16 -1 (-1575 2525)(-1400 2525);
WIRE 16 -1 (-1575 2675)(-1400 2675);
WIRE 16 -1 (-200 4075)(-25 4075);
WIRE 16 -1 (5900 4075)(6150 4075);
WIRE 16 -1 (5900 4025)(6150 4025);
WIRE 16 -1 (6150 4075)(6150 4025);
WIRE 16 -1 (5900 3975)(6150 3975);
WIRE 16 -1 (6150 4025)(6150 3975);
WIRE 16 -1 (5900 3925)(6150 3925);
WIRE 16 -1 (6150 3975)(6150 3925);
WIRE 16 -1 (5900 3875)(6150 3875);
WIRE 16 -1 (6150 3925)(6150 3875);
WIRE 16 -1 (5900 3825)(6150 3825);
WIRE 16 -1 (6150 3875)(6150 3825);
WIRE 16 -1 (5900 3775)(6150 3775);
WIRE 16 -1 (6150 3825)(6150 3775);
WIRE 16 -1 (5900 3725)(6150 3725);
WIRE 16 -1 (6150 3775)(6150 3725);
WIRE 16 -1 (5900 3675)(6150 3675);
WIRE 16 -1 (6150 3725)(6150 3675);
WIRE 16 -1 (5900 3625)(6150 3625);
WIRE 16 -1 (6150 3675)(6150 3625);
WIRE 16 -1 (5900 3575)(6150 3575);
WIRE 16 -1 (6150 3625)(6150 3575);
WIRE 16 -1 (5900 3525)(6150 3525);
WIRE 16 -1 (6150 3575)(6150 3525);
WIRE 16 -1 (5900 3475)(6150 3475);
WIRE 16 -1 (6150 3525)(6150 3475);
WIRE 16 -1 (5900 3425)(6150 3425);
WIRE 16 -1 (6150 3475)(6150 3425);
WIRE 16 -1 (5900 3375)(6150 3375);
WIRE 16 -1 (6150 3425)(6150 3375);
WIRE 16 -1 (5900 3325)(6150 3325);
WIRE 16 -1 (6150 3325)(6150 3375);
WIRE 16 -1 (5900 3275)(6150 3275);
WIRE 16 -1 (6150 3325)(6150 3275);
WIRE 16 -1 (6150 3225)(5900 3225);
WIRE 16 -1 (6150 3275)(6150 3225);
WIRE 16 -1 (6150 3175)(5900 3175);
WIRE 16 -1 (6150 3225)(6150 3175);
WIRE 16 -1 (5900 3125)(6150 3125);
WIRE 16 -1 (6150 3175)(6150 3125);
WIRE 16 -1 (5900 3075)(6150 3075);
WIRE 16 -1 (6150 3125)(6150 3075);
WIRE 16 -1 (5900 3025)(6150 3025);
WIRE 16 -1 (6150 3075)(6150 3025);
WIRE 16 -1 (5900 2975)(6150 2975);
WIRE 16 -1 (6150 3025)(6150 2975);
WIRE 16 -1 (5900 2925)(6150 2925);
WIRE 16 -1 (6150 2975)(6150 2925);
WIRE 16 -1 (5900 2875)(6150 2875);
WIRE 16 -1 (6150 2925)(6150 2875);
WIRE 16 -1 (5900 2825)(6150 2825);
WIRE 16 -1 (6150 2825)(6150 2875);
WIRE 16 -1 (5900 2775)(6150 2775);
WIRE 16 -1 (6150 2825)(6150 2775);
WIRE 16 -1 (6150 2725)(5900 2725);
WIRE 16 -1 (6150 2775)(6150 2725);
WIRE 16 -1 (6150 2675)(5900 2675);
WIRE 16 -1 (6150 2725)(6150 2675);
WIRE 16 -1 (5900 2625)(6150 2625);
WIRE 16 -1 (6150 2675)(6150 2625);
WIRE 16 -1 (5900 2575)(6150 2575);
WIRE 16 -1 (6150 2625)(6150 2575);
WIRE 16 -1 (5900 2525)(6150 2525);
WIRE 16 -1 (6150 2575)(6150 2525);
WIRE 16 -1 (5900 2475)(6150 2475);
WIRE 16 -1 (6150 2525)(6150 2475);
WIRE 16 -1 (5900 2425)(6150 2425);
WIRE 16 -1 (6150 2475)(6150 2425);
WIRE 16 -1 (5900 2375)(6150 2375);
WIRE 16 -1 (6150 2425)(6150 2375);
WIRE 16 -1 (5900 2325)(6150 2325);
WIRE 16 -1 (6150 2325)(6150 2375);
WIRE 16 -1 (5900 2275)(6150 2275);
WIRE 16 -1 (6150 2325)(6150 2275);
WIRE 16 -1 (6150 2225)(5900 2225);
WIRE 16 -1 (6150 2275)(6150 2225);
WIRE 16 -1 (6150 2175)(5900 2175);
WIRE 16 -1 (6150 2225)(6150 2175);
WIRE 16 -1 (5900 2125)(6150 2125);
WIRE 16 -1 (6150 2175)(6150 2125);
WIRE 16 -1 (5900 2075)(6150 2075);
WIRE 16 -1 (6150 2125)(6150 2075);
WIRE 16 -1 (5900 2025)(6150 2025);
WIRE 16 -1 (6150 2075)(6150 2025);
WIRE 16 -1 (5900 1975)(6150 1975);
WIRE 16 -1 (6150 2025)(6150 1975);
WIRE 16 -1 (5900 1925)(6150 1925);
WIRE 16 -1 (6150 1975)(6150 1925);
WIRE 16 -1 (5900 1875)(6150 1875);
WIRE 16 -1 (6150 1925)(6150 1875);
WIRE 16 -1 (5900 1825)(6150 1825);
WIRE 16 -1 (6150 1825)(6150 1875);
WIRE 16 -1 (5900 1775)(6150 1775);
WIRE 16 -1 (6150 1825)(6150 1775);
WIRE 16 -1 (6150 1725)(5900 1725);
WIRE 16 -1 (6150 1775)(6150 1725);
WIRE 16 -1 (6150 1675)(5900 1675);
WIRE 16 -1 (6150 1725)(6150 1675);
WIRE 16 -1 (6150 1625)(5900 1625);
WIRE 16 -1 (6150 1675)(6150 1625);
WIRE 16 -1 (6150 1575)(5900 1575);
WIRE 16 -1 (6150 1625)(6150 1575);
WIRE 16 -1 (5900 1525)(6150 1525);
WIRE 16 -1 (6150 1525)(6150 1575);
WIRE 16 -1 (6150 1475)(5900 1475);
WIRE 16 -1 (6150 1475)(6150 1525);
WIRE 16 -1 (6150 1425)(5900 1425);
WIRE 16 -1 (6150 1475)(6150 1425);
WIRE 16 -1 (6150 1375)(5900 1375);
WIRE 16 -1 (6150 1425)(6150 1375);
WIRE 16 -1 (5900 1325)(6150 1325);
WIRE 16 -1 (6150 1375)(6150 1325);
WIRE 16 -1 (5900 1275)(6150 1275);
WIRE 16 -1 (6150 1325)(6150 1275);
WIRE 16 -1 (5900 1225)(6150 1225);
WIRE 16 -1 (6150 1275)(6150 1225);
WIRE 16 -1 (5900 1175)(6150 1175);
WIRE 16 -1 (6150 1225)(6150 1175);
WIRE 16 -1 (5900 1125)(6150 1125);
WIRE 16 -1 (6150 1175)(6150 1125);
WIRE 16 -1 (5900 1075)(6150 1075);
WIRE 16 -1 (6150 1125)(6150 1075);
WIRE 16 -1 (5900 1025)(6150 1025);
WIRE 16 -1 (6150 1075)(6150 1025);
WIRE 16 -1 (5900 975)(6150 975);
WIRE 16 -1 (6150 975)(6150 1025);
WIRE 16 -1 (5900 925)(6150 925);
WIRE 16 -1 (6150 975)(6150 925);
WIRE 16 -1 (5900 825)(6150 825);
WIRE 16 -1 (6150 925)(6150 825);
WIRE 16 -1 (6150 825)(6150 775);
WIRE 16 -1 (5900 775)(6150 775);
WIRE 16 -1 (-1400 125)(-2500 125);
FORCEPROP 2 LAST SIG_NAME PD_CHA_CPU1_DIMM1_SAA
J 0
(-2412 134);
DISPLAY 0.680851 (-2412 134);
PAINT WHITE (-2412 134);
WIRE 16 -1 (-1400 25)(-1400 125);
WIRE 16 -1 (2750 425)(2750 300);
WIRE 16 -1 (3375 425)(2750 425);
WIRE 16 -1 (3375 300)(3375 425);
WIRE 16 -1 (3375 -50)(3375 100);
WIRE 16 -1 (3375 -50)(2750 -50);
WIRE 16 -1 (2750 -50)(2750 100);
WIRE 16 3135 (1400 700)(1400 -600);
WIRE 16 3135 (4000 700)(1400 700);
WIRE 16 3135 (1400 -600)(4000 -600);
WIRE 16 3135 (4000 -600)(4000 700);
DOT 1 (6150 725);
DOT 1 (6150 775);
DOT 1 (6150 825);
DOT 1 (6150 4025);
DOT 1 (6150 3975);
DOT 1 (6150 3925);
DOT 1 (6150 3875);
DOT 1 (6150 3775);
DOT 1 (6150 3825);
DOT 1 (6150 3725);
DOT 1 (6150 3675);
DOT 1 (6150 3625);
DOT 1 (6150 3525);
DOT 1 (6150 3575);
DOT 1 (6150 3475);
DOT 1 (6150 3425);
DOT 1 (6150 3375);
DOT 1 (6150 3325);
DOT 1 (6150 3275);
DOT 1 (6150 3225);
DOT 1 (6150 3175);
DOT 1 (6150 3125);
DOT 1 (6150 3025);
DOT 1 (6150 3075);
DOT 1 (6150 2875);
DOT 1 (6150 2925);
DOT 1 (6150 2975);
DOT 1 (6150 2825);
DOT 1 (6150 2775);
DOT 1 (6150 2725);
DOT 1 (6150 2625);
DOT 1 (6150 2675);
DOT 1 (6150 2575);
DOT 1 (6150 2525);
DOT 1 (6150 2475);
DOT 1 (6150 2375);
DOT 1 (6150 2425);
DOT 1 (6150 2325);
DOT 1 (6150 2275);
DOT 1 (6150 2225);
DOT 1 (6150 2125);
DOT 1 (6150 2175);
DOT 1 (6150 2075);
DOT 1 (6150 2025);
DOT 1 (6150 1975);
DOT 1 (6150 1925);
DOT 1 (6150 1875);
DOT 1 (6150 1825);
DOT 1 (6150 1725);
DOT 1 (6150 1775);
DOT 1 (6150 1675);
DOT 1 (6150 1625);
DOT 1 (6150 1575);
DOT 1 (6150 1475);
DOT 1 (6150 1525);
DOT 1 (6150 1425);
DOT 1 (6150 1325);
DOT 1 (6150 1375);
DOT 1 (6150 1275);
DOT 1 (6150 1225);
DOT 1 (6150 1175);
DOT 1 (6150 1125);
DOT 1 (6150 1075);
DOT 1 (6150 975);
DOT 1 (6150 1025);
DOT 1 (6150 925);
DOT 1 (4450 4075);
DOT 1 (4450 4025);
DOT 1 (4450 3875);
DOT 1 (4450 3825);
DOT 1 (4450 3775);
DOT 1 (4450 3725);
DOT 1 (4450 3625);
DOT 1 (4450 3575);
DOT 1 (4450 3525);
DOT 1 (4450 3475);
DOT 1 (4450 3375);
DOT 1 (4450 3425);
DOT 1 (4450 3325);
DOT 1 (4450 3275);
DOT 1 (4450 3225);
DOT 1 (4450 3175);
DOT 1 (4450 3125);
DOT 1 (4450 3075);
DOT 1 (4450 2975);
DOT 1 (4450 2925);
DOT 1 (4450 2875);
DOT 1 (4450 2825);
DOT 1 (4450 2775);
DOT 1 (4450 2725);
DOT 1 (4450 2675);
DOT 1 (4450 2625);
DOT 1 (4450 2575);
DOT 1 (4450 2525);
DOT 1 (4450 2475);
DOT 1 (4450 2425);
DOT 1 (4450 2375);
DOT 1 (4450 2325);
DOT 1 (4450 2275);
DOT 1 (4450 2225);
DOT 1 (4450 2175);
DOT 1 (4450 2125);
DOT 1 (4450 2075);
DOT 1 (4450 1925);
DOT 1 (4450 1875);
DOT 1 (4450 1825);
DOT 1 (4450 1775);
DOT 1 (4450 1725);
DOT 1 (4450 1675);
DOT 1 (4450 1625);
DOT 1 (4450 1575);
DOT 1 (4450 1525);
DOT 1 (4450 1475);
DOT 1 (4450 1425);
DOT 1 (4450 1375);
DOT 1 (4450 1325);
DOT 1 (4450 1275);
DOT 1 (4450 1225);
DOT 1 (4450 1175);
DOT 1 (4450 1125);
DOT 1 (4450 1075);
DOT 1 (4450 1025);
DOT 1 (4450 925);
DOT 1 (4450 975);
DOT 1 (4450 825);
DOT 1 (4450 875);
DOT 1 (2750 425);
DOT 1 (3375 -50);
DOT 1 (4450 3675);
DOT 1 (4450 3025);
DOT 1 (4450 1975);
DOT 1 (4450 2025);
FORCENOTE
20210728 MODIFY FOR GT
(-2925 4750) 0;
DISPLAY LEFT (-2925 4750);
DISPLAY 2.510638 (-2925 4750);
PAINT PINK (-2925 4750);
QUIT
